FILE_TYPE = MACRO_DRAWING;
SET COLOR_WIRE YELLOW;
SET COLOR_PROP ORANGE;
SET COLOR_DOT WHITE;
SET COLOR_ARC YELLOW;
SET COLOR_BODY GREEN;
SET COLOR_NOTE PURPLE;
SET PROP_DISPLAY VALUE;
SET PAGE_NUMBER P141;
FORCEADD SN74AVC4T774PWR..1
(-4525 3300);
FORCEPROP 1 LAST LOCATION U116
J 0
(-4772 3865);
DISPLAY 0.723404 (-4772 3865);
PAINT GREEN (-4772 3865);
FORCEPROP 0 LAST $SEC 1
J 0
(-4775 3975);
DISPLAY 0.680851 (-4775 3975);
PAINT MONO (-4775 3975);
DISPLAY INVISIBLE (-4775 3975);
FORCEPROP 0 LAST CDS_SEC 1
J 0
(-4750 3850);
DISPLAY 1.021277 (-4750 3850);
DISPLAY INVISIBLE (-4750 3850);
FORCEPROP 0 LASTPIN (-4925 3450) $PN 3
J 2
(-4935 3460);
DISPLAY 0.680851 (-4935 3460);
PAINT MONO (-4935 3460);
FORCEPROP 0 LASTPIN (-4925 3400) $PN 4
J 2
(-4935 3410);
DISPLAY 0.680851 (-4935 3410);
PAINT MONO (-4935 3410);
FORCEPROP 0 LASTPIN (-4925 3350) $PN 5
J 2
(-4935 3360);
DISPLAY 0.680851 (-4935 3360);
PAINT MONO (-4935 3360);
FORCEPROP 0 LASTPIN (-4925 3300) $PN 6
J 2
(-4935 3310);
DISPLAY 0.680851 (-4935 3310);
PAINT MONO (-4935 3310);
FORCEPROP 0 LASTPIN (-4125 3450) $PN 14
J 0
(-4115 3460);
DISPLAY 0.680851 (-4115 3460);
PAINT MONO (-4115 3460);
FORCEPROP 0 LASTPIN (-4125 3400) $PN 13
J 0
(-4115 3410);
DISPLAY 0.680851 (-4115 3410);
PAINT MONO (-4115 3410);
FORCEPROP 0 LASTPIN (-4125 3350) $PN 12
J 0
(-4115 3360);
DISPLAY 0.680851 (-4115 3360);
PAINT MONO (-4115 3360);
FORCEPROP 0 LASTPIN (-4125 3300) $PN 11
J 0
(-4115 3310);
DISPLAY 0.680851 (-4115 3310);
PAINT MONO (-4115 3310);
FORCEPROP 0 LASTPIN (-4925 3150) $PN 1
J 2
(-4935 3160);
DISPLAY 0.680851 (-4935 3160);
PAINT MONO (-4935 3160);
FORCEPROP 0 LASTPIN (-4925 3100) $PN 2
J 2
(-4935 3110);
DISPLAY 0.680851 (-4935 3110);
PAINT MONO (-4935 3110);
FORCEPROP 0 LASTPIN (-4925 3050) $PN 7
J 2
(-4935 3060);
DISPLAY 0.680851 (-4935 3060);
PAINT MONO (-4935 3060);
FORCEPROP 0 LASTPIN (-4925 3000) $PN 8
J 2
(-4935 3010);
DISPLAY 0.680851 (-4935 3010);
PAINT MONO (-4935 3010);
FORCEPROP 0 LASTPIN (-4125 2900) $PN 10
J 0
(-4115 2910);
DISPLAY 0.680851 (-4115 2910);
PAINT MONO (-4115 2910);
FORCEPROP 0 LASTPIN (-4925 2950) $PN 9
J 2
(-4935 2960);
DISPLAY 0.680851 (-4935 2960);
PAINT MONO (-4935 2960);
FORCEPROP 0 LASTPIN (-4925 3650) $PN 16
J 2
(-4935 3660);
DISPLAY 0.680851 (-4935 3660);
PAINT MONO (-4935 3660);
FORCEPROP 0 LASTPIN (-4125 3650) $PN 15
J 0
(-4115 3660);
DISPLAY 0.680851 (-4115 3660);
PAINT MONO (-4115 3660);
FORCEPROP 2 LAST VALUE SN74AVC4T774PWR
J 0
(-4750 3750);
DISPLAY 0.489362 (-4750 3750);
PAINT SKYBLUE (-4750 3750);
FORCEPROP 1 LAST MATERIAL IC
J 0
(-4350 3800);
DISPLAY 0.723404 (-4350 3800);
PAINT GREEN (-4350 3800);
FORCEPROP 2 LAST PART_TYPE SMLF
J 0
(-4775 3925);
DISPLAY 1.021277 (-4775 3925);
FORCEPROP 2 LAST CDS_LIB pure_quanta
J 0
(-4525 3300);
DISPLAY INVISIBLE (-4525 3300);
FORCEPROP 1 LAST NEEDS_NO_SIZE TRUE
J 0
(-4525 3300);
DISPLAY 0.723404 (-4525 3300);
PAINT GREEN (-4525 3300);
DISPLAY INVISIBLE (-4525 3300);
FORCEPROP 1 LAST CDS_LMAN_SYM_OUTLINE -250,450,250,-450
J 0
(-4525 3300);
DISPLAY 0.468085 (-4525 3300);
PAINT GREEN (-4525 3300);
DISPLAY INVISIBLE (-4525 3300);
FORCEPROP 1 LAST PATH I117
J 0
(-4525 3300);
DISPLAY 0.723404 (-4525 3300);
PAINT GREEN (-4525 3300);
DISPLAY INVISIBLE (-4525 3300);
FORCEPROP 1 LAST PART_NUMBER AL04T774K00
J 0
(-4772 3808);
DISPLAY 0.723404 (-4772 3808);
PAINT GREEN (-4772 3808);
DISPLAY INVISIBLE (-4772 3808);
FORCEADD UNIVERSAL_POWER..1
(-1250 4700);
FORCEPROP 3 LASTPIN (-1250 4650) SIG_NAME P3V3_AUX\g
J 0
(-1240 4660);
DISPLAY 0.659574 (-1240 4660);
PAINT MONO (-1240 4660);
DISPLAY INVISIBLE (-1240 4660);
FORCEPROP 1 LAST HDL_POWER P3V3_AUX
J 1
(-1250 4750);
DISPLAY 0.489362 (-1250 4750);
PAINT GREEN (-1250 4750);
FORCEPROP 2 LAST CDS_LIB pure_quanta_power
J 0
(-1250 4700);
DISPLAY INVISIBLE (-1250 4700);
FORCEPROP 1 LAST PATH I120
J 0
(-1200 4725);
DISPLAY 0.872340 (-1200 4725);
PAINT AQUA (-1200 4725);
DISPLAY INVISIBLE (-1200 4725);
FORCEADD OFFPAGE..2
R 2
(-2175 4225);
FORCEPROP 2 LAST $XR2 151 
J 0
(-2670 4225);
DISPLAY 0.638298 (-2670 4225);
PAINT MONO (-2670 4225);
FORCEPROP 2 LAST $XR1 150 
J 0
(-2550 4225);
DISPLAY 0.638298 (-2550 4225);
PAINT MONO (-2550 4225);
FORCEPROP 2 LAST $XR0 164 
J 0
(-2430 4225);
DISPLAY 0.638298 (-2430 4225);
PAINT MONO (-2430 4225);
FORCEPROP 2 LAST CDS_LIB standard
J 2
(-2175 4225);
DISPLAY INVISIBLE (-2175 4225);
FORCEPROP 1 LAST OFFPAGE TRUE
J 2
(-2500 4100);
DISPLAY 0.872340 (-2500 4100);
PAINT GREEN (-2500 4100);
DISPLAY INVISIBLE (-2500 4100);
FORCEPROP 1 LAST COMMENT_BODY TRUE
J 2
(-2130 4130);
DISPLAY 0.872340 (-2130 4130);
PAINT PEACH (-2130 4130);
DISPLAY INVISIBLE (-2130 4130);
FORCEPROP 2 LAST PATH I126
J 0
(-2425 4275);
DISPLAY 1.021277 (-2425 4275);
DISPLAY INVISIBLE (-2425 4275);
FORCEADD UNIVERSAL_POWER..1
(-4000 3975);
FORCEPROP 3 LASTPIN (-4000 3925) SIG_NAME P3V3_AUX\g
J 0
(-3990 3935);
DISPLAY 0.659574 (-3990 3935);
PAINT MONO (-3990 3935);
DISPLAY INVISIBLE (-3990 3935);
FORCEPROP 1 LAST HDL_POWER P3V3_AUX
J 1
(-4000 4025);
DISPLAY 0.489362 (-4000 4025);
PAINT GREEN (-4000 4025);
FORCEPROP 2 LAST CDS_LIB pure_quanta_power
J 0
(-4000 3975);
DISPLAY INVISIBLE (-4000 3975);
FORCEPROP 1 LAST PATH I128
J 0
(-3950 4000);
DISPLAY 0.872340 (-3950 4000);
PAINT AQUA (-3950 4000);
DISPLAY INVISIBLE (-3950 4000);
FORCEADD Q_CAP..1
(-3850 3725);
FORCEPROP 1 LAST LOCATION C1354
J 0
(-3800 3825);
DISPLAY 0.489362 (-3800 3825);
PAINT SKYBLUE (-3800 3825);
FORCEPROP 0 LAST $SEC 1
J 0
(-3800 3850);
DISPLAY 0.680851 (-3800 3850);
PAINT MONO (-3800 3850);
DISPLAY INVISIBLE (-3800 3850);
FORCEPROP 0 LAST CDS_SEC 1
J 0
(-3800 3850);
DISPLAY 1.021277 (-3800 3850);
DISPLAY INVISIBLE (-3800 3850);
FORCEPROP 1 LASTPIN (-3850 3825) $PN 1
J 0
(-3840 3805);
DISPLAY 0.489362 (-3840 3805);
PAINT MONO (-3840 3805);
FORCEPROP 1 LASTPIN (-3850 3625) $PN 2
J 0
(-3840 3605);
DISPLAY 0.489362 (-3840 3605);
PAINT MONO (-3840 3605);
FORCEPROP 1 LAST PACK_TYPE 0402
J 0
(-3800 3650);
DISPLAY 0.489362 (-3800 3650);
PAINT SKYBLUE (-3800 3650);
FORCEPROP 1 LAST MATERIAL X7R
J 0
(-3800 3700);
DISPLAY 0.489362 (-3800 3700);
PAINT SKYBLUE (-3800 3700);
FORCEPROP 1 LAST TOLERANCE 10%
J 0
(-3800 3725);
DISPLAY 0.489362 (-3800 3725);
PAINT SKYBLUE (-3800 3725);
FORCEPROP 1 LAST VALUE 0.1UF
J 0
(-3800 3775);
DISPLAY 0.489362 (-3800 3775);
PAINT SKYBLUE (-3800 3775);
FORCEPROP 1 LAST VOLTAGE 25V
J 0
(-3800 3750);
DISPLAY 0.489362 (-3800 3750);
PAINT SKYBLUE (-3800 3750);
FORCEPROP 2 LAST CDS_LIB pure_quanta
J 2
(-3850 3725);
DISPLAY INVISIBLE (-3850 3725);
FORCEPROP 1 LAST PATH I133
J 0
(-3800 3875);
DISPLAY 0.978723 (-3800 3875);
PAINT WHITE (-3800 3875);
DISPLAY INVISIBLE (-3800 3875);
FORCEPROP 1 LAST PART_NUMBER CH4104K1B00
J 0
(-3800 3675);
DISPLAY 0.489362 (-3800 3675);
PAINT SKYBLUE (-3800 3675);
DISPLAY INVISIBLE (-3800 3675);
FORCEADD UNIVERSAL_GND..1
R 2
(-3850 3525);
FORCEPROP 3 LASTPIN (-3850 3575) SIG_NAME GND\g
J 0
(-3840 3585);
DISPLAY 0.659574 (-3840 3585);
PAINT MONO (-3840 3585);
DISPLAY INVISIBLE (-3840 3585);
FORCEPROP 2 LAST CDS_LIB pure_quanta_power
J 2
(-3850 3525);
DISPLAY INVISIBLE (-3850 3525);
FORCEPROP 1 LAST HDL_POWER GND
J 1
(-3875 3450);
DISPLAY 0.872340 (-3875 3450);
PAINT GREEN (-3875 3450);
DISPLAY INVISIBLE (-3875 3450);
FORCEPROP 1 LAST PATH I134
J 2
(-3925 3525);
DISPLAY 0.872340 (-3925 3525);
PAINT AQUA (-3925 3525);
DISPLAY INVISIBLE (-3925 3525);
FORCEADD UNIVERSAL_POWER..1
(-5050 3950);
FORCEPROP 3 LASTPIN (-5050 3900) SIG_NAME PVDD18_S5_P0\g
J 0
(-5040 3910);
DISPLAY 0.659574 (-5040 3910);
PAINT MONO (-5040 3910);
DISPLAY INVISIBLE (-5040 3910);
FORCEPROP 1 LAST HDL_POWER PVDD18_S5_P0
J 1
(-5050 4000);
DISPLAY 0.489362 (-5050 4000);
PAINT GREEN (-5050 4000);
FORCEPROP 2 LAST CDS_LIB pure_quanta_power
J 0
(-5050 3950);
DISPLAY INVISIBLE (-5050 3950);
FORCEPROP 1 LAST PATH I135
J 0
(-5000 3975);
DISPLAY 0.872340 (-5000 3975);
PAINT AQUA (-5000 3975);
DISPLAY INVISIBLE (-5000 3975);
FORCEADD UNIVERSAL_GND..1
(-5175 3525);
FORCEPROP 3 LASTPIN (-5175 3575) SIG_NAME GND\g
J 0
(-5165 3585);
DISPLAY 0.659574 (-5165 3585);
PAINT MONO (-5165 3585);
DISPLAY INVISIBLE (-5165 3585);
FORCEPROP 2 LAST CDS_LIB pure_quanta_power
J 0
(-5175 3525);
PAINT MONO (-5175 3525);
DISPLAY INVISIBLE (-5175 3525);
FORCEPROP 1 LAST HDL_POWER GND
J 1
(-5150 3450);
DISPLAY 0.872340 (-5150 3450);
PAINT GREEN (-5150 3450);
DISPLAY INVISIBLE (-5150 3450);
FORCEPROP 1 LAST PATH I136
J 0
(-5100 3525);
DISPLAY 0.872340 (-5100 3525);
PAINT AQUA (-5100 3525);
DISPLAY INVISIBLE (-5100 3525);
FORCEADD Q_CAP..1
R 2
(-5175 3725);
FORCEPROP 1 LAST LOCATION C1352
J 2
(-5225 3800);
DISPLAY 0.489362 (-5225 3800);
PAINT SKYBLUE (-5225 3800);
FORCEPROP 2 LAST $SEC 1
J 0
(-5225 3925);
DISPLAY 0.680851 (-5225 3925);
PAINT MONO (-5225 3925);
DISPLAY INVISIBLE (-5225 3925);
FORCEPROP 2 LAST CDS_SEC 1
J 0
(-5225 3925);
DISPLAY 1.021277 (-5225 3925);
DISPLAY INVISIBLE (-5225 3925);
FORCEPROP 1 LASTPIN (-5175 3825) $PN 1
J 2
(-5185 3805);
DISPLAY 0.489362 (-5185 3805);
FORCEPROP 1 LASTPIN (-5175 3625) $PN 2
J 2
(-5185 3605);
DISPLAY 0.489362 (-5185 3605);
FORCEPROP 1 LAST VALUE 0.1UF
J 2
(-5225 3775);
DISPLAY 0.489362 (-5225 3775);
PAINT SKYBLUE (-5225 3775);
FORCEPROP 1 LAST PACK_TYPE 0402
J 2
(-5225 3650);
DISPLAY 0.489362 (-5225 3650);
PAINT SKYBLUE (-5225 3650);
FORCEPROP 1 LAST MATERIAL X7R
J 2
(-5225 3700);
DISPLAY 0.489362 (-5225 3700);
PAINT SKYBLUE (-5225 3700);
FORCEPROP 1 LAST VOLTAGE 25V
J 2
(-5225 3750);
DISPLAY 0.489362 (-5225 3750);
PAINT SKYBLUE (-5225 3750);
FORCEPROP 1 LAST TOLERANCE 10%
J 2
(-5225 3725);
DISPLAY 0.489362 (-5225 3725);
PAINT SKYBLUE (-5225 3725);
FORCEPROP 2 LAST CDS_LIB pure_quanta
J 0
(-5175 3725);
PAINT MONO (-5175 3725);
DISPLAY INVISIBLE (-5175 3725);
FORCEPROP 1 LAST PATH I137
J 2
(-5225 3875);
DISPLAY 0.978723 (-5225 3875);
PAINT WHITE (-5225 3875);
DISPLAY INVISIBLE (-5225 3875);
FORCEPROP 1 LAST PART_NUMBER CH4104K1B00
J 2
(-5225 3675);
DISPLAY 0.489362 (-5225 3675);
PAINT SKYBLUE (-5225 3675);
DISPLAY INVISIBLE (-5225 3675);
FORCEADD OFFPAGE..2
(-6300 3950);
FORCEPROP 2 LAST $XR1 27 
J 0
(-5991 3950);
DISPLAY 0.638298 (-5991 3950);
PAINT MONO (-5991 3950);
FORCEPROP 2 LAST $XR0 164 
J 0
(-6111 3950);
DISPLAY 0.638298 (-6111 3950);
PAINT MONO (-6111 3950);
FORCEPROP 2 LAST CDS_LIB standard
J 0
(-6300 3950);
DISPLAY INVISIBLE (-6300 3950);
FORCEPROP 1 LAST OFFPAGE TRUE
J 0
(-5975 3825);
DISPLAY 0.872340 (-5975 3825);
PAINT GREEN (-5975 3825);
DISPLAY INVISIBLE (-5975 3825);
FORCEPROP 1 LAST COMMENT_BODY TRUE
J 0
(-6345 3855);
DISPLAY 0.872340 (-6345 3855);
PAINT PEACH (-6345 3855);
DISPLAY INVISIBLE (-6345 3855);
FORCEPROP 2 LAST PATH I138
J 0
(-5925 4000);
DISPLAY 1.021277 (-5925 4000);
DISPLAY INVISIBLE (-5925 4000);
FORCEADD UNIVERSAL_POWER..1
(-7425 4425);
FORCEPROP 3 LASTPIN (-7425 4375) SIG_NAME PVDD18_S5_P0\g
J 0
(-7415 4385);
DISPLAY 0.659574 (-7415 4385);
PAINT MONO (-7415 4385);
DISPLAY INVISIBLE (-7415 4385);
FORCEPROP 1 LAST HDL_POWER PVDD18_S5_P0
J 1
(-7425 4475);
DISPLAY 0.489362 (-7425 4475);
PAINT GREEN (-7425 4475);
FORCEPROP 2 LAST CDS_LIB pure_quanta_power
J 0
(-7425 4425);
DISPLAY INVISIBLE (-7425 4425);
FORCEPROP 1 LAST PATH I145
J 0
(-7375 4450);
DISPLAY 0.872340 (-7375 4450);
PAINT AQUA (-7375 4450);
DISPLAY INVISIBLE (-7375 4450);
FORCEADD UNIVERSAL_POWER..1
(-6875 2750);
FORCEPROP 3 LASTPIN (-6875 2700) SIG_NAME PVDD18_S5_P0\g
J 0
(-6865 2710);
DISPLAY 0.659574 (-6865 2710);
PAINT MONO (-6865 2710);
DISPLAY INVISIBLE (-6865 2710);
FORCEPROP 1 LAST HDL_POWER PVDD18_S5_P0
J 1
(-6875 2800);
DISPLAY 0.489362 (-6875 2800);
PAINT GREEN (-6875 2800);
FORCEPROP 2 LAST CDS_LIB pure_quanta_power
J 0
(-6875 2750);
DISPLAY INVISIBLE (-6875 2750);
FORCEPROP 1 LAST PATH I148
J 0
(-6825 2775);
DISPLAY 0.872340 (-6825 2775);
PAINT AQUA (-6825 2775);
DISPLAY INVISIBLE (-6825 2775);
FORCEADD UNIVERSAL_GND..1
R 2
(-1975 1175);
FORCEPROP 3 LASTPIN (-1975 1225) SIG_NAME GND\g
J 0
(-1965 1235);
DISPLAY 0.659574 (-1965 1235);
PAINT MONO (-1965 1235);
DISPLAY INVISIBLE (-1965 1235);
FORCEPROP 2 LAST CDS_LIB pure_quanta_power
J 0
(-1975 1175);
DISPLAY INVISIBLE (-1975 1175);
FORCEPROP 1 LAST HDL_POWER GND
J 1
(-2000 1100);
DISPLAY 0.872340 (-2000 1100);
PAINT GREEN (-2000 1100);
DISPLAY INVISIBLE (-2000 1100);
FORCEPROP 1 LAST PATH I180
J 2
(-2050 1175);
DISPLAY 0.872340 (-2050 1175);
PAINT AQUA (-2050 1175);
DISPLAY INVISIBLE (-2050 1175);
FORCEADD UNIVERSAL_POWER..1
(-2150 1325);
FORCEPROP 3 LASTPIN (-2150 1275) SIG_NAME P3V3_AUX\g
J 0
(-2140 1285);
DISPLAY 0.659574 (-2140 1285);
PAINT MONO (-2140 1285);
DISPLAY INVISIBLE (-2140 1285);
FORCEPROP 1 LAST HDL_POWER P3V3_AUX
J 1
(-2150 1375);
DISPLAY 0.489362 (-2150 1375);
PAINT GREEN (-2150 1375);
FORCEPROP 2 LAST CDS_LIB pure_quanta_power
J 0
(-2150 1325);
DISPLAY INVISIBLE (-2150 1325);
FORCEPROP 2 LAST BOM_COST VR_SYSTEM 
J 0
(-2150 1425);
DISPLAY 0.680851 (-2150 1425);
DISPLAY INVISIBLE (-2150 1425);
FORCEPROP 1 LAST PATH I181
J 0
(-2100 1350);
DISPLAY 0.872340 (-2100 1350);
PAINT AQUA (-2100 1350);
DISPLAY INVISIBLE (-2100 1350);
FORCEADD P1V0..1
(-2375 1325);
FORCEPROP 3 LASTPIN (-2375 1275) SIG_NAME P5V_AUX\g
J 0
(-2365 1285);
DISPLAY 0.659574 (-2365 1285);
PAINT MONO (-2365 1285);
DISPLAY INVISIBLE (-2365 1285);
FORCEPROP 1 LAST HDL_POWER P5V_AUX
J 1
(-2375 1375);
DISPLAY 0.489362 (-2375 1375);
PAINT GREEN (-2375 1375);
FORCEPROP 2 LAST CDS_LIB pure_quanta_power
J 0
(-2375 1325);
DISPLAY INVISIBLE (-2375 1325);
FORCEPROP 1 LAST PATH I182
J 0
(-2325 1350);
DISPLAY 0.872340 (-2325 1350);
PAINT AQUA (-2325 1350);
DISPLAY INVISIBLE (-2325 1350);
FORCEADD OFFPAGE..1
(-3925 1475);
FORCEPROP 2 LAST $XR0 164 
J 0
(-4177 1475);
DISPLAY 0.638298 (-4177 1475);
PAINT MONO (-4177 1475);
FORCEPROP 2 LAST CDS_LIB standard
J 0
(-3925 1475);
DISPLAY INVISIBLE (-3925 1475);
FORCEPROP 1 LAST OFFPAGE TRUE
J 0
(-3600 1350);
DISPLAY 0.872340 (-3600 1350);
PAINT GREEN (-3600 1350);
DISPLAY INVISIBLE (-3600 1350);
FORCEPROP 1 LAST COMMENT_BODY TRUE
J 0
(-3800 1375);
DISPLAY 0.872340 (-3800 1375);
PAINT GREEN (-3800 1375);
DISPLAY INVISIBLE (-3800 1375);
FORCEPROP 2 LAST PATH I184
J 0
(-3875 1550);
DISPLAY 1.021277 (-3875 1550);
DISPLAY INVISIBLE (-3875 1550);
FORCEADD Q_RES..2
(-2150 1075);
FORCEPROP 1 LAST LOCATION R821
J 0
(-2105 1200);
DISPLAY 0.489362 (-2105 1200);
PAINT SKYBLUE (-2105 1200);
FORCEPROP 2 LAST $SEC 1
J 0
(-2100 1300);
DISPLAY 0.680851 (-2100 1300);
PAINT MONO (-2100 1300);
DISPLAY INVISIBLE (-2100 1300);
FORCEPROP 2 LAST CDS_SEC 1
J 0
(-2100 1300);
DISPLAY 0.680851 (-2100 1300);
DISPLAY INVISIBLE (-2100 1300);
FORCEPROP 1 LASTPIN (-2150 1175) $PN 1
J 0
(-2145 1137);
DISPLAY 0.489362 (-2145 1137);
PAINT MONO (-2145 1137);
FORCEPROP 1 LASTPIN (-2150 975) $PN 2
J 0
(-2145 985);
DISPLAY 0.489362 (-2145 985);
PAINT MONO (-2145 985);
FORCEPROP 1 LAST PACK_TYPE 0402LF
J 0
(-2125 1025);
DISPLAY 0.489362 (-2125 1025);
PAINT SKYBLUE (-2125 1025);
FORCEPROP 1 LAST VALUE 10K
J 0
(-2125 1125);
DISPLAY 0.489362 (-2125 1125);
PAINT SKYBLUE (-2125 1125);
FORCEPROP 1 LAST TOLERANCE 5%
J 0
(-2125 1100);
DISPLAY 0.489362 (-2125 1100);
PAINT SKYBLUE (-2125 1100);
FORCEPROP 1 LAST MATERIAL CHIP
J 0
(-2125 1050);
DISPLAY 0.489362 (-2125 1050);
PAINT SKYBLUE (-2125 1050);
FORCEPROP 1 LAST WATTAGE 1/16W
J 0
(-2125 1075);
DISPLAY 0.489362 (-2125 1075);
PAINT SKYBLUE (-2125 1075);
FORCEPROP 2 LAST CDS_LIB pure_quanta
J 0
(-2150 1075);
DISPLAY INVISIBLE (-2150 1075);
FORCEPROP 1 LAST PATH I185
J 0
(-2100 1250);
DISPLAY 0.978723 (-2100 1250);
PAINT WHITE (-2100 1250);
DISPLAY INVISIBLE (-2100 1250);
FORCEPROP 1 LAST PART_NUMBER CS31002JB08
J 2
(-2175 1000);
DISPLAY 0.489362 (-2175 1000);
PAINT SKYBLUE (-2175 1000);
DISPLAY INVISIBLE (-2175 1000);
FORCEADD Q_RES..1
R 1
(-2375 1100);
FORCEPROP 1 LAST LOCATION R820
R 1
J 0
(-2425 1050);
DISPLAY 0.489362 (-2425 1050);
PAINT SKYBLUE (-2425 1050);
FORCEPROP 2 LAST $SEC 1
J 0
(-2325 1200);
DISPLAY 0.680851 (-2325 1200);
PAINT MONO (-2325 1200);
DISPLAY INVISIBLE (-2325 1200);
FORCEPROP 2 LAST CDS_SEC 1
J 0
(-2325 1200);
DISPLAY 0.680851 (-2325 1200);
DISPLAY INVISIBLE (-2325 1200);
FORCEPROP 1 LASTPIN (-2375 1000) $PN 1
R 1
J 0
(-2387 1012);
DISPLAY 0.489362 (-2387 1012);
PAINT MONO (-2387 1012);
FORCEPROP 1 LASTPIN (-2375 1200) $PN 2
R 1
J 0
(-2387 1162);
DISPLAY 0.489362 (-2387 1162);
PAINT MONO (-2387 1162);
FORCEPROP 1 LAST PACK_TYPE 0402LF
J 0
(-2325 1025);
DISPLAY 0.489362 (-2325 1025);
PAINT SKYBLUE (-2325 1025);
FORCEPROP 1 LAST TOLERANCE 5%
J 0
(-2325 1125);
DISPLAY 0.489362 (-2325 1125);
PAINT SKYBLUE (-2325 1125);
FORCEPROP 1 LAST MATERIAL EMPTY
J 0
(-2325 975);
DISPLAY 0.489362 (-2325 975);
PAINT RED (-2325 975);
FORCEPROP 1 LAST WATTAGE 1/16W
J 0
(-2325 1075);
DISPLAY 0.489362 (-2325 1075);
PAINT SKYBLUE (-2325 1075);
FORCEPROP 1 LAST VALUE 10K
J 0
(-2325 1175);
DISPLAY 0.489362 (-2325 1175);
PAINT SKYBLUE (-2325 1175);
FORCEPROP 2 LAST CDS_LIB pure_quanta
J 0
(-2375 1100);
DISPLAY INVISIBLE (-2375 1100);
FORCEPROP 1 LAST PATH I186
R 1
J 0
(-2525 1050);
DISPLAY 0.978723 (-2525 1050);
PAINT WHITE (-2525 1050);
DISPLAY INVISIBLE (-2525 1050);
FORCEPROP 1 LAST PART_NUMBER CS31002JB08
R 1
J 0
(-2475 1050);
DISPLAY 0.638298 (-2475 1050);
PAINT SKYBLUE (-2475 1050);
DISPLAY INVISIBLE (-2475 1050);
FORCEADD Q_CAP..1
(-2575 1150);
FORCEPROP 1 LAST LOCATION C364
J 0
(-2525 1250);
DISPLAY 0.489362 (-2525 1250);
PAINT SKYBLUE (-2525 1250);
FORCEPROP 2 LAST $SEC 1
J 0
(-2525 1350);
DISPLAY 0.680851 (-2525 1350);
PAINT MONO (-2525 1350);
DISPLAY INVISIBLE (-2525 1350);
FORCEPROP 2 LAST CDS_SEC 1
J 0
(-2525 1350);
DISPLAY 0.680851 (-2525 1350);
DISPLAY INVISIBLE (-2525 1350);
FORCEPROP 1 LASTPIN (-2575 1250) $PN 1
J 0
(-2565 1230);
DISPLAY 0.489362 (-2565 1230);
PAINT MONO (-2565 1230);
FORCEPROP 1 LASTPIN (-2575 1050) $PN 2
J 0
(-2565 1030);
DISPLAY 0.489362 (-2565 1030);
PAINT MONO (-2565 1030);
FORCEPROP 1 LAST TOLERANCE 5%
J 0
(-2525 1100);
DISPLAY 0.489362 (-2525 1100);
PAINT SKYBLUE (-2525 1100);
FORCEPROP 1 LAST VOLTAGE 50V
J 0
(-2525 1150);
DISPLAY 0.489362 (-2525 1150);
PAINT SKYBLUE (-2525 1150);
FORCEPROP 1 LAST PACK_TYPE C0402
J 0
(-2525 1050);
DISPLAY 0.489362 (-2525 1050);
PAINT SKYBLUE (-2525 1050);
FORCEPROP 1 LAST VALUE 220PF
J 0
(-2525 1200);
DISPLAY 0.489362 (-2525 1200);
PAINT SKYBLUE (-2525 1200);
FORCEPROP 2 LAST CDS_LIB pure_quanta
J 0
(-2575 1150);
DISPLAY INVISIBLE (-2575 1150);
FORCEPROP 1 LAST MATERIAL C0G
J 0
(-2525 1050);
DISPLAY 0.404255 (-2525 1050);
PAINT SKYBLUE (-2525 1050);
DISPLAY INVISIBLE (-2525 1050);
FORCEPROP 1 LAST PATH I187
J 0
(-2525 1300);
DISPLAY 0.978723 (-2525 1300);
PAINT WHITE (-2525 1300);
DISPLAY INVISIBLE (-2525 1300);
FORCEPROP 1 LAST PART_NUMBER CH12206JB00
J 0
(-2525 1000);
DISPLAY 0.404255 (-2525 1000);
PAINT SKYBLUE (-2525 1000);
DISPLAY INVISIBLE (-2525 1000);
FORCEADD UNIVERSAL_GND..1
R 2
(-2575 950);
FORCEPROP 3 LASTPIN (-2575 1000) SIG_NAME GND\g
J 0
(-2565 1010);
DISPLAY 0.659574 (-2565 1010);
PAINT MONO (-2565 1010);
DISPLAY INVISIBLE (-2565 1010);
FORCEPROP 2 LAST CDS_LIB pure_quanta_power
J 0
(-2575 950);
DISPLAY INVISIBLE (-2575 950);
FORCEPROP 1 LAST HDL_POWER GND
J 1
(-2600 875);
DISPLAY 0.872340 (-2600 875);
PAINT GREEN (-2600 875);
DISPLAY INVISIBLE (-2600 875);
FORCEPROP 1 LAST PATH I188
J 2
(-2650 950);
DISPLAY 0.872340 (-2650 950);
PAINT AQUA (-2650 950);
DISPLAY INVISIBLE (-2650 950);
FORCEADD UNIVERSAL_GND..1
R 2
(-2775 950);
FORCEPROP 3 LASTPIN (-2775 1000) SIG_NAME GND\g
J 0
(-2765 1010);
DISPLAY 0.659574 (-2765 1010);
PAINT MONO (-2765 1010);
DISPLAY INVISIBLE (-2765 1010);
FORCEPROP 2 LAST CDS_LIB pure_quanta_power
J 0
(-2775 950);
DISPLAY INVISIBLE (-2775 950);
FORCEPROP 1 LAST HDL_POWER GND
J 1
(-2800 875);
DISPLAY 0.872340 (-2800 875);
PAINT GREEN (-2800 875);
DISPLAY INVISIBLE (-2800 875);
FORCEPROP 1 LAST PATH I189
J 2
(-2850 950);
DISPLAY 0.872340 (-2850 950);
PAINT AQUA (-2850 950);
DISPLAY INVISIBLE (-2850 950);
FORCEADD Q_CAP..1
(-2775 1150);
FORCEPROP 1 LAST LOCATION C363
J 0
(-2725 1250);
DISPLAY 0.489362 (-2725 1250);
PAINT SKYBLUE (-2725 1250);
FORCEPROP 2 LAST $SEC 1
J 0
(-2725 1350);
DISPLAY 0.680851 (-2725 1350);
PAINT MONO (-2725 1350);
DISPLAY INVISIBLE (-2725 1350);
FORCEPROP 2 LAST CDS_SEC 1
J 0
(-2725 1350);
DISPLAY 0.680851 (-2725 1350);
DISPLAY INVISIBLE (-2725 1350);
FORCEPROP 1 LASTPIN (-2775 1250) $PN 1
J 0
(-2765 1230);
DISPLAY 0.489362 (-2765 1230);
PAINT MONO (-2765 1230);
FORCEPROP 1 LASTPIN (-2775 1050) $PN 2
J 0
(-2765 1030);
DISPLAY 0.489362 (-2765 1030);
PAINT MONO (-2765 1030);
FORCEPROP 1 LAST PACK_TYPE C0402
J 0
(-2725 1050);
DISPLAY 0.489362 (-2725 1050);
PAINT SKYBLUE (-2725 1050);
FORCEPROP 1 LAST TOLERANCE 5%
J 0
(-2725 1100);
DISPLAY 0.489362 (-2725 1100);
PAINT SKYBLUE (-2725 1100);
FORCEPROP 1 LAST VALUE 220PF
J 0
(-2725 1200);
DISPLAY 0.489362 (-2725 1200);
PAINT SKYBLUE (-2725 1200);
FORCEPROP 1 LAST VOLTAGE 50V
J 0
(-2725 1150);
DISPLAY 0.489362 (-2725 1150);
PAINT SKYBLUE (-2725 1150);
FORCEPROP 2 LAST CDS_LIB pure_quanta
J 0
(-2775 1150);
DISPLAY INVISIBLE (-2775 1150);
FORCEPROP 1 LAST MATERIAL C0G
J 0
(-2725 1050);
DISPLAY 0.404255 (-2725 1050);
PAINT SKYBLUE (-2725 1050);
DISPLAY INVISIBLE (-2725 1050);
FORCEPROP 1 LAST PATH I190
J 0
(-2725 1300);
DISPLAY 0.978723 (-2725 1300);
PAINT WHITE (-2725 1300);
DISPLAY INVISIBLE (-2725 1300);
FORCEPROP 1 LAST PART_NUMBER CH12206JB00
J 0
(-2725 1000);
DISPLAY 0.404255 (-2725 1000);
PAINT SKYBLUE (-2725 1000);
DISPLAY INVISIBLE (-2725 1000);
FORCEADD CONN4_HFK1040L0P1L7H..1
(-1325 1450);
FORCEPROP 1 LAST LOCATION J13
J 0
(-1400 1725);
DISPLAY 0.489362 (-1400 1725);
PAINT SKYBLUE (-1400 1725);
FORCEPROP 2 LAST $SEC 1
J 0
(-1400 1875);
DISPLAY 0.680851 (-1400 1875);
PAINT MONO (-1400 1875);
DISPLAY INVISIBLE (-1400 1875);
FORCEPROP 2 LAST CDS_SEC 1
J 0
(-1400 1875);
DISPLAY 0.680851 (-1400 1875);
DISPLAY INVISIBLE (-1400 1875);
FORCEPROP 2 LASTPIN (-1550 1375) $PN 1
J 2
(-1560 1385);
DISPLAY 0.489362 (-1560 1385);
PAINT MONO (-1560 1385);
FORCEPROP 2 LASTPIN (-1550 1425) $PN 2
J 2
(-1560 1435);
DISPLAY 0.489362 (-1560 1435);
PAINT MONO (-1560 1435);
FORCEPROP 2 LASTPIN (-1550 1475) $PN 3
J 2
(-1560 1485);
DISPLAY 0.489362 (-1560 1485);
PAINT MONO (-1560 1485);
FORCEPROP 2 LASTPIN (-1550 1525) $PN 4
J 2
(-1560 1535);
DISPLAY 0.489362 (-1560 1535);
PAINT MONO (-1560 1535);
FORCEPROP 2 LAST PART_TYPE THLF
J 0
(-1400 1825);
DISPLAY 1.021277 (-1400 1825);
FORCEPROP 1 LAST MATERIAL IO
J 0
(-1398 1591);
DISPLAY 0.489362 (-1398 1591);
PAINT SKYBLUE (-1398 1591);
FORCEPROP 2 LAST VALUE CONN4_HFK1040-L0P1L-7H
J 0
(-1400 1775);
DISPLAY 0.489362 (-1400 1775);
PAINT SKYBLUE (-1400 1775);
FORCEPROP 2 LAST CDS_LIB pure_quanta
J 0
(-1325 1450);
DISPLAY INVISIBLE (-1325 1450);
FORCEPROP 1 LAST CDS_LMAN_SYM_OUTLINE -75,125,75,-125
J 0
(-1325 1450);
DISPLAY 0.468085 (-1325 1450);
PAINT GREEN (-1325 1450);
DISPLAY INVISIBLE (-1325 1450);
FORCEPROP 1 LAST NEEDS_NO_SIZE TRUE
J 0
(-1325 1450);
DISPLAY 0.723404 (-1325 1450);
PAINT GREEN (-1325 1450);
DISPLAY INVISIBLE (-1325 1450);
FORCEPROP 1 LAST PATH I195
J 0
(-1325 1450);
DISPLAY 0.723404 (-1325 1450);
PAINT GREEN (-1325 1450);
DISPLAY INVISIBLE (-1325 1450);
FORCEPROP 1 LAST PART_NUMBER DFHD04MS460
J 0
(-1400 1650);
DISPLAY 0.489362 (-1400 1650);
PAINT SKYBLUE (-1400 1650);
DISPLAY INVISIBLE (-1400 1650);
FORCEADD Q_RES..2
(-7425 4125);
FORCEPROP 1 LAST LOCATION R816
J 0
(-7380 4250);
DISPLAY 0.489362 (-7380 4250);
PAINT SKYBLUE (-7380 4250);
FORCEPROP 2 LAST $SEC 1
J 0
(-7375 4350);
DISPLAY 0.680851 (-7375 4350);
PAINT MONO (-7375 4350);
DISPLAY INVISIBLE (-7375 4350);
FORCEPROP 2 LAST CDS_SEC 1
J 0
(-7375 4350);
DISPLAY 0.680851 (-7375 4350);
DISPLAY INVISIBLE (-7375 4350);
FORCEPROP 1 LASTPIN (-7425 4225) $PN 1
J 0
(-7420 4187);
DISPLAY 0.489362 (-7420 4187);
PAINT MONO (-7420 4187);
FORCEPROP 1 LASTPIN (-7425 4025) $PN 2
J 0
(-7420 4035);
DISPLAY 0.489362 (-7420 4035);
PAINT MONO (-7420 4035);
FORCEPROP 1 LAST MATERIAL CHIP
J 0
(-7375 4100);
DISPLAY 0.489362 (-7375 4100);
PAINT SKYBLUE (-7375 4100);
FORCEPROP 1 LAST VALUE 10K
J 0
(-7375 4175);
DISPLAY 0.489362 (-7375 4175);
PAINT SKYBLUE (-7375 4175);
FORCEPROP 1 LAST WATTAGE 1/16W
J 0
(-7375 4125);
DISPLAY 0.489362 (-7375 4125);
PAINT SKYBLUE (-7375 4125);
FORCEPROP 1 LAST PACK_TYPE 0402LF
J 0
(-7375 4075);
DISPLAY 0.489362 (-7375 4075);
PAINT SKYBLUE (-7375 4075);
FORCEPROP 1 LAST TOLERANCE 5%
J 0
(-7375 4150);
DISPLAY 0.489362 (-7375 4150);
PAINT SKYBLUE (-7375 4150);
FORCEPROP 2 LAST CDS_LIB pure_quanta
J 2
(-7425 4125);
DISPLAY INVISIBLE (-7425 4125);
FORCEPROP 1 LAST PATH I196
J 0
(-7375 4300);
DISPLAY 0.978723 (-7375 4300);
PAINT WHITE (-7375 4300);
DISPLAY INVISIBLE (-7375 4300);
FORCEPROP 1 LAST PART_NUMBER CS31002JB08
J 0
(-7375 4050);
DISPLAY 0.489362 (-7375 4050);
PAINT SKYBLUE (-7375 4050);
DISPLAY INVISIBLE (-7375 4050);
FORCEADD Q_RES..2
(-7625 4125);
FORCEPROP 1 LAST LOCATION R815
J 0
(-7580 4250);
DISPLAY 0.489362 (-7580 4250);
PAINT SKYBLUE (-7580 4250);
FORCEPROP 2 LAST $SEC 1
J 0
(-7575 4350);
DISPLAY 0.680851 (-7575 4350);
PAINT MONO (-7575 4350);
DISPLAY INVISIBLE (-7575 4350);
FORCEPROP 2 LAST CDS_SEC 1
J 0
(-7575 4350);
DISPLAY 0.680851 (-7575 4350);
DISPLAY INVISIBLE (-7575 4350);
FORCEPROP 1 LASTPIN (-7625 4225) $PN 1
J 0
(-7620 4187);
DISPLAY 0.489362 (-7620 4187);
PAINT MONO (-7620 4187);
FORCEPROP 1 LASTPIN (-7625 4025) $PN 2
J 0
(-7620 4035);
DISPLAY 0.489362 (-7620 4035);
PAINT MONO (-7620 4035);
FORCEPROP 1 LAST VALUE 10K
J 0
(-7575 4175);
DISPLAY 0.489362 (-7575 4175);
PAINT SKYBLUE (-7575 4175);
FORCEPROP 1 LAST MATERIAL EMPTY
J 0
(-7575 4100);
DISPLAY 0.489362 (-7575 4100);
PAINT RED (-7575 4100);
FORCEPROP 1 LAST PACK_TYPE 0402LF
J 0
(-7575 4075);
DISPLAY 0.489362 (-7575 4075);
PAINT SKYBLUE (-7575 4075);
FORCEPROP 1 LAST TOLERANCE 5%
J 0
(-7575 4150);
DISPLAY 0.489362 (-7575 4150);
PAINT SKYBLUE (-7575 4150);
FORCEPROP 1 LAST WATTAGE 1/16W
J 0
(-7575 4125);
DISPLAY 0.489362 (-7575 4125);
PAINT SKYBLUE (-7575 4125);
FORCEPROP 2 LAST CDS_LIB pure_quanta
J 0
(-7625 4125);
DISPLAY INVISIBLE (-7625 4125);
FORCEPROP 1 LAST PATH I197
J 0
(-7575 4300);
DISPLAY 0.978723 (-7575 4300);
PAINT WHITE (-7575 4300);
DISPLAY INVISIBLE (-7575 4300);
FORCEPROP 1 LAST PART_NUMBER CS31002JB08
J 0
(-7575 4050);
DISPLAY 0.489362 (-7575 4050);
PAINT SKYBLUE (-7575 4050);
DISPLAY INVISIBLE (-7575 4050);
FORCEADD Q_RES..2
(-7850 4125);
FORCEPROP 1 LAST LOCATION R814
J 0
(-7805 4250);
DISPLAY 0.489362 (-7805 4250);
PAINT SKYBLUE (-7805 4250);
FORCEPROP 2 LAST $SEC 1
J 0
(-7800 4350);
DISPLAY 0.680851 (-7800 4350);
PAINT MONO (-7800 4350);
DISPLAY INVISIBLE (-7800 4350);
FORCEPROP 2 LAST CDS_SEC 1
J 0
(-7800 4350);
DISPLAY 0.680851 (-7800 4350);
DISPLAY INVISIBLE (-7800 4350);
FORCEPROP 1 LASTPIN (-7850 4225) $PN 1
J 0
(-7845 4187);
DISPLAY 0.489362 (-7845 4187);
PAINT MONO (-7845 4187);
FORCEPROP 1 LASTPIN (-7850 4025) $PN 2
J 0
(-7845 4035);
DISPLAY 0.489362 (-7845 4035);
PAINT MONO (-7845 4035);
FORCEPROP 1 LAST VALUE 10K
J 0
(-7800 4175);
DISPLAY 0.489362 (-7800 4175);
PAINT SKYBLUE (-7800 4175);
FORCEPROP 1 LAST PACK_TYPE 0402LF
J 0
(-7800 4075);
DISPLAY 0.489362 (-7800 4075);
PAINT SKYBLUE (-7800 4075);
FORCEPROP 1 LAST MATERIAL EMPTY
J 0
(-7800 4100);
DISPLAY 0.489362 (-7800 4100);
PAINT RED (-7800 4100);
FORCEPROP 1 LAST WATTAGE 1/16W
J 0
(-7800 4125);
DISPLAY 0.489362 (-7800 4125);
PAINT SKYBLUE (-7800 4125);
FORCEPROP 1 LAST TOLERANCE 5%
J 0
(-7800 4150);
DISPLAY 0.489362 (-7800 4150);
PAINT SKYBLUE (-7800 4150);
FORCEPROP 2 LAST CDS_LIB pure_quanta
J 0
(-7850 4125);
DISPLAY INVISIBLE (-7850 4125);
FORCEPROP 1 LAST PATH I198
J 0
(-7800 4300);
DISPLAY 0.978723 (-7800 4300);
PAINT WHITE (-7800 4300);
DISPLAY INVISIBLE (-7800 4300);
FORCEPROP 1 LAST PART_NUMBER CS31002JB08
J 0
(-7800 4050);
DISPLAY 0.489362 (-7800 4050);
PAINT SKYBLUE (-7800 4050);
DISPLAY INVISIBLE (-7800 4050);
FORCEADD Q_RES..2
(-8050 4125);
FORCEPROP 1 LAST LOCATION R813
J 0
(-8005 4250);
DISPLAY 0.489362 (-8005 4250);
PAINT SKYBLUE (-8005 4250);
FORCEPROP 2 LAST $SEC 1
J 0
(-8000 4350);
DISPLAY 0.680851 (-8000 4350);
PAINT MONO (-8000 4350);
DISPLAY INVISIBLE (-8000 4350);
FORCEPROP 2 LAST CDS_SEC 1
J 0
(-8000 4350);
DISPLAY 0.680851 (-8000 4350);
DISPLAY INVISIBLE (-8000 4350);
FORCEPROP 1 LASTPIN (-8050 4225) $PN 1
J 0
(-8045 4187);
DISPLAY 0.489362 (-8045 4187);
PAINT MONO (-8045 4187);
FORCEPROP 1 LASTPIN (-8050 4025) $PN 2
J 0
(-8045 4035);
DISPLAY 0.489362 (-8045 4035);
PAINT MONO (-8045 4035);
FORCEPROP 1 LAST MATERIAL CHIP
J 0
(-8000 4100);
DISPLAY 0.489362 (-8000 4100);
PAINT SKYBLUE (-8000 4100);
FORCEPROP 1 LAST PACK_TYPE 0402LF
J 0
(-8000 4075);
DISPLAY 0.489362 (-8000 4075);
PAINT SKYBLUE (-8000 4075);
FORCEPROP 1 LAST WATTAGE 1/16W
J 0
(-8000 4125);
DISPLAY 0.489362 (-8000 4125);
PAINT SKYBLUE (-8000 4125);
FORCEPROP 1 LAST VALUE 10K
J 0
(-8000 4175);
DISPLAY 0.489362 (-8000 4175);
PAINT SKYBLUE (-8000 4175);
FORCEPROP 1 LAST TOLERANCE 5%
J 0
(-8000 4150);
DISPLAY 0.489362 (-8000 4150);
PAINT SKYBLUE (-8000 4150);
FORCEPROP 2 LAST CDS_LIB pure_quanta
J 0
(-8050 4125);
DISPLAY INVISIBLE (-8050 4125);
FORCEPROP 1 LAST PATH I199
J 0
(-8000 4300);
DISPLAY 0.978723 (-8000 4300);
PAINT WHITE (-8000 4300);
DISPLAY INVISIBLE (-8000 4300);
FORCEPROP 1 LAST PART_NUMBER CS31002JB08
J 0
(-8000 4050);
DISPLAY 0.489362 (-8000 4050);
PAINT SKYBLUE (-8000 4050);
DISPLAY INVISIBLE (-8000 4050);
FORCEADD OFFPAGE..2
(-6300 3875);
FORCEPROP 2 LAST $XR2 164 
J 0
(-5931 3875);
DISPLAY 0.638298 (-5931 3875);
PAINT MONO (-5931 3875);
FORCEPROP 2 LAST $XR1 76 
J 0
(-6021 3875);
DISPLAY 0.638298 (-6021 3875);
PAINT MONO (-6021 3875);
FORCEPROP 2 LAST $XR0 27 
J 0
(-6111 3875);
DISPLAY 0.638298 (-6111 3875);
PAINT MONO (-6111 3875);
FORCEPROP 2 LAST CDS_LIB standard
J 0
(-6300 3875);
DISPLAY INVISIBLE (-6300 3875);
FORCEPROP 1 LAST OFFPAGE TRUE
J 0
(-5975 3750);
DISPLAY 0.872340 (-5975 3750);
PAINT GREEN (-5975 3750);
DISPLAY INVISIBLE (-5975 3750);
FORCEPROP 1 LAST COMMENT_BODY TRUE
J 0
(-6345 3780);
DISPLAY 0.872340 (-6345 3780);
PAINT PEACH (-6345 3780);
DISPLAY INVISIBLE (-6345 3780);
FORCEPROP 2 LAST PATH I200
J 0
(-6125 3950);
DISPLAY 1.021277 (-6125 3950);
DISPLAY INVISIBLE (-6125 3950);
FORCEADD OFFPAGE..2
(-6300 3800);
FORCEPROP 2 LAST $XR1 164 
J 0
(-6021 3800);
DISPLAY 0.638298 (-6021 3800);
PAINT MONO (-6021 3800);
FORCEPROP 2 LAST $XR0 27 
J 0
(-6111 3800);
DISPLAY 0.638298 (-6111 3800);
PAINT MONO (-6111 3800);
FORCEPROP 2 LAST CDS_LIB standard
J 0
(-6300 3800);
DISPLAY INVISIBLE (-6300 3800);
FORCEPROP 1 LAST OFFPAGE TRUE
J 0
(-5975 3675);
DISPLAY 0.872340 (-5975 3675);
PAINT GREEN (-5975 3675);
DISPLAY INVISIBLE (-5975 3675);
FORCEPROP 1 LAST COMMENT_BODY TRUE
J 0
(-6345 3705);
DISPLAY 0.872340 (-6345 3705);
PAINT PEACH (-6345 3705);
DISPLAY INVISIBLE (-6345 3705);
FORCEPROP 2 LAST PATH I201
J 0
(-6125 3875);
DISPLAY 1.021277 (-6125 3875);
DISPLAY INVISIBLE (-6125 3875);
FORCEADD OFFPAGE..2
(-6300 3750);
FORCEPROP 2 LAST $XR1 27 
J 0
(-5991 3750);
DISPLAY 0.638298 (-5991 3750);
PAINT MONO (-5991 3750);
FORCEPROP 2 LAST $XR0 164 
J 0
(-6111 3750);
DISPLAY 0.638298 (-6111 3750);
PAINT MONO (-6111 3750);
FORCEPROP 2 LAST CDS_LIB standard
J 0
(-6300 3750);
DISPLAY INVISIBLE (-6300 3750);
FORCEPROP 1 LAST OFFPAGE TRUE
J 0
(-5975 3625);
DISPLAY 0.872340 (-5975 3625);
PAINT GREEN (-5975 3625);
DISPLAY INVISIBLE (-5975 3625);
FORCEPROP 1 LAST COMMENT_BODY TRUE
J 0
(-6345 3655);
DISPLAY 0.872340 (-6345 3655);
PAINT PEACH (-6345 3655);
DISPLAY INVISIBLE (-6345 3655);
FORCEPROP 2 LAST PATH I202
J 0
(-6125 3825);
DISPLAY 1.021277 (-6125 3825);
DISPLAY INVISIBLE (-6125 3825);
FORCEADD Q_RES..2
(-625 4425);
FORCEPROP 1 LAST LOCATION R825
J 0
(-580 4550);
DISPLAY 0.489362 (-580 4550);
PAINT SKYBLUE (-580 4550);
FORCEPROP 2 LAST $SEC 1
J 0
(-575 4650);
DISPLAY 0.680851 (-575 4650);
PAINT MONO (-575 4650);
DISPLAY INVISIBLE (-575 4650);
FORCEPROP 2 LAST CDS_SEC 1
J 0
(-575 4650);
DISPLAY 0.680851 (-575 4650);
DISPLAY INVISIBLE (-575 4650);
FORCEPROP 1 LASTPIN (-625 4525) $PN 1
J 0
(-620 4487);
DISPLAY 0.489362 (-620 4487);
PAINT MONO (-620 4487);
FORCEPROP 1 LASTPIN (-625 4325) $PN 2
J 0
(-620 4335);
DISPLAY 0.489362 (-620 4335);
PAINT MONO (-620 4335);
FORCEPROP 1 LAST VALUE 10K
J 0
(-575 4475);
DISPLAY 0.489362 (-575 4475);
PAINT SKYBLUE (-575 4475);
FORCEPROP 1 LAST PACK_TYPE 0402LF
J 0
(-575 4375);
DISPLAY 0.489362 (-575 4375);
PAINT SKYBLUE (-575 4375);
FORCEPROP 1 LAST MATERIAL EMPTY
J 0
(-575 4400);
DISPLAY 0.489362 (-575 4400);
PAINT RED (-575 4400);
FORCEPROP 1 LAST WATTAGE 1/16W
J 0
(-575 4425);
DISPLAY 0.489362 (-575 4425);
PAINT SKYBLUE (-575 4425);
FORCEPROP 1 LAST TOLERANCE 5%
J 0
(-575 4450);
DISPLAY 0.489362 (-575 4450);
PAINT SKYBLUE (-575 4450);
FORCEPROP 2 LAST CDS_LIB pure_quanta
J 0
(-625 4425);
DISPLAY INVISIBLE (-625 4425);
FORCEPROP 1 LAST PATH I203
J 0
(-575 4600);
DISPLAY 0.978723 (-575 4600);
PAINT WHITE (-575 4600);
DISPLAY INVISIBLE (-575 4600);
FORCEPROP 1 LAST PART_NUMBER CS31002JB08
J 0
(-575 4350);
DISPLAY 0.489362 (-575 4350);
PAINT SKYBLUE (-575 4350);
DISPLAY INVISIBLE (-575 4350);
FORCEADD Q_RES..2
(-825 4425);
FORCEPROP 1 LAST LOCATION R824
J 0
(-780 4550);
DISPLAY 0.489362 (-780 4550);
PAINT SKYBLUE (-780 4550);
FORCEPROP 2 LAST $SEC 1
J 0
(-775 4650);
DISPLAY 0.680851 (-775 4650);
PAINT MONO (-775 4650);
DISPLAY INVISIBLE (-775 4650);
FORCEPROP 2 LAST CDS_SEC 1
J 0
(-775 4650);
DISPLAY 0.680851 (-775 4650);
DISPLAY INVISIBLE (-775 4650);
FORCEPROP 1 LASTPIN (-825 4525) $PN 1
J 0
(-820 4487);
DISPLAY 0.489362 (-820 4487);
PAINT MONO (-820 4487);
FORCEPROP 1 LASTPIN (-825 4325) $PN 2
J 0
(-820 4335);
DISPLAY 0.489362 (-820 4335);
PAINT MONO (-820 4335);
FORCEPROP 1 LAST MATERIAL CHIP
J 0
(-775 4400);
DISPLAY 0.489362 (-775 4400);
PAINT SKYBLUE (-775 4400);
FORCEPROP 1 LAST PACK_TYPE 0402LF
J 0
(-775 4375);
DISPLAY 0.489362 (-775 4375);
PAINT SKYBLUE (-775 4375);
FORCEPROP 1 LAST VALUE 10K
J 0
(-775 4475);
DISPLAY 0.489362 (-775 4475);
PAINT SKYBLUE (-775 4475);
FORCEPROP 1 LAST TOLERANCE 5%
J 0
(-775 4450);
DISPLAY 0.489362 (-775 4450);
PAINT SKYBLUE (-775 4450);
FORCEPROP 1 LAST WATTAGE 1/16W
J 0
(-775 4425);
DISPLAY 0.489362 (-775 4425);
PAINT SKYBLUE (-775 4425);
FORCEPROP 2 LAST CDS_LIB pure_quanta
J 0
(-825 4425);
DISPLAY INVISIBLE (-825 4425);
FORCEPROP 1 LAST PATH I204
J 0
(-775 4600);
DISPLAY 0.978723 (-775 4600);
PAINT WHITE (-775 4600);
DISPLAY INVISIBLE (-775 4600);
FORCEPROP 1 LAST PART_NUMBER CS31002JB08
J 0
(-775 4350);
DISPLAY 0.489362 (-775 4350);
PAINT SKYBLUE (-775 4350);
DISPLAY INVISIBLE (-775 4350);
FORCEADD Q_RES..2
(-1050 4425);
FORCEPROP 1 LAST LOCATION R823
J 0
(-1005 4550);
DISPLAY 0.489362 (-1005 4550);
PAINT SKYBLUE (-1005 4550);
FORCEPROP 2 LAST $SEC 1
J 0
(-1000 4650);
DISPLAY 0.680851 (-1000 4650);
PAINT MONO (-1000 4650);
DISPLAY INVISIBLE (-1000 4650);
FORCEPROP 2 LAST CDS_SEC 1
J 0
(-1000 4650);
DISPLAY 0.680851 (-1000 4650);
DISPLAY INVISIBLE (-1000 4650);
FORCEPROP 1 LASTPIN (-1050 4525) $PN 1
J 0
(-1045 4487);
DISPLAY 0.489362 (-1045 4487);
PAINT MONO (-1045 4487);
FORCEPROP 1 LASTPIN (-1050 4325) $PN 2
J 0
(-1045 4335);
DISPLAY 0.489362 (-1045 4335);
PAINT MONO (-1045 4335);
FORCEPROP 1 LAST WATTAGE 1/16W
J 0
(-1000 4425);
DISPLAY 0.489362 (-1000 4425);
PAINT SKYBLUE (-1000 4425);
FORCEPROP 1 LAST TOLERANCE 5%
J 0
(-1000 4450);
DISPLAY 0.489362 (-1000 4450);
PAINT SKYBLUE (-1000 4450);
FORCEPROP 1 LAST MATERIAL EMPTY
J 0
(-1000 4400);
DISPLAY 0.489362 (-1000 4400);
PAINT RED (-1000 4400);
FORCEPROP 1 LAST PACK_TYPE 0402LF
J 0
(-1000 4375);
DISPLAY 0.489362 (-1000 4375);
PAINT SKYBLUE (-1000 4375);
FORCEPROP 1 LAST VALUE 10K
J 0
(-1000 4475);
DISPLAY 0.489362 (-1000 4475);
PAINT SKYBLUE (-1000 4475);
FORCEPROP 2 LAST CDS_LIB pure_quanta
J 0
(-1050 4425);
DISPLAY INVISIBLE (-1050 4425);
FORCEPROP 1 LAST PATH I205
J 0
(-1000 4600);
DISPLAY 0.978723 (-1000 4600);
PAINT WHITE (-1000 4600);
DISPLAY INVISIBLE (-1000 4600);
FORCEPROP 1 LAST PART_NUMBER CS31002JB08
J 0
(-1000 4350);
DISPLAY 0.489362 (-1000 4350);
PAINT SKYBLUE (-1000 4350);
DISPLAY INVISIBLE (-1000 4350);
FORCEADD Q_RES..2
(-1250 4425);
FORCEPROP 1 LAST LOCATION R822
J 0
(-1205 4550);
DISPLAY 0.489362 (-1205 4550);
PAINT SKYBLUE (-1205 4550);
FORCEPROP 2 LAST $SEC 1
J 0
(-1200 4650);
DISPLAY 0.680851 (-1200 4650);
PAINT MONO (-1200 4650);
DISPLAY INVISIBLE (-1200 4650);
FORCEPROP 2 LAST CDS_SEC 1
J 0
(-1200 4650);
DISPLAY 0.680851 (-1200 4650);
DISPLAY INVISIBLE (-1200 4650);
FORCEPROP 1 LASTPIN (-1250 4525) $PN 1
J 0
(-1245 4487);
DISPLAY 0.489362 (-1245 4487);
PAINT MONO (-1245 4487);
FORCEPROP 1 LASTPIN (-1250 4325) $PN 2
J 0
(-1245 4335);
DISPLAY 0.489362 (-1245 4335);
PAINT MONO (-1245 4335);
FORCEPROP 1 LAST MATERIAL CHIP
J 0
(-1200 4400);
DISPLAY 0.489362 (-1200 4400);
PAINT SKYBLUE (-1200 4400);
FORCEPROP 1 LAST VALUE 10K
J 0
(-1200 4475);
DISPLAY 0.489362 (-1200 4475);
PAINT SKYBLUE (-1200 4475);
FORCEPROP 1 LAST TOLERANCE 5%
J 0
(-1200 4450);
DISPLAY 0.489362 (-1200 4450);
PAINT SKYBLUE (-1200 4450);
FORCEPROP 1 LAST WATTAGE 1/16W
J 0
(-1200 4425);
DISPLAY 0.489362 (-1200 4425);
PAINT SKYBLUE (-1200 4425);
FORCEPROP 1 LAST PACK_TYPE 0402LF
J 0
(-1200 4375);
DISPLAY 0.489362 (-1200 4375);
PAINT SKYBLUE (-1200 4375);
FORCEPROP 2 LAST CDS_LIB pure_quanta
J 0
(-1250 4425);
DISPLAY INVISIBLE (-1250 4425);
FORCEPROP 1 LAST PATH I206
J 0
(-1200 4600);
DISPLAY 0.978723 (-1200 4600);
PAINT WHITE (-1200 4600);
DISPLAY INVISIBLE (-1200 4600);
FORCEPROP 1 LAST PART_NUMBER CS31002JB08
J 0
(-1200 4350);
DISPLAY 0.489362 (-1200 4350);
PAINT SKYBLUE (-1200 4350);
DISPLAY INVISIBLE (-1200 4350);
FORCEADD OFFPAGE..2
R 2
(-2175 4175);
FORCEPROP 2 LAST $XR2 164 
J 0
(-2670 4175);
DISPLAY 0.638298 (-2670 4175);
PAINT MONO (-2670 4175);
FORCEPROP 2 LAST $XR1 151 
J 0
(-2550 4175);
DISPLAY 0.638298 (-2550 4175);
PAINT MONO (-2550 4175);
FORCEPROP 2 LAST $XR0 150 
J 0
(-2430 4175);
DISPLAY 0.638298 (-2430 4175);
PAINT MONO (-2430 4175);
FORCEPROP 2 LAST CDS_LIB standard
J 0
(-2175 4175);
DISPLAY INVISIBLE (-2175 4175);
FORCEPROP 1 LAST OFFPAGE TRUE
J 2
(-2500 4050);
DISPLAY 0.872340 (-2500 4050);
PAINT GREEN (-2500 4050);
DISPLAY INVISIBLE (-2500 4050);
FORCEPROP 1 LAST COMMENT_BODY TRUE
J 2
(-2130 4080);
DISPLAY 0.872340 (-2130 4080);
PAINT PEACH (-2130 4080);
DISPLAY INVISIBLE (-2130 4080);
FORCEPROP 2 LAST PATH I207
J 0
(-2125 4250);
DISPLAY 1.021277 (-2125 4250);
DISPLAY INVISIBLE (-2125 4250);
FORCEADD OFFPAGE..2
R 2
(-2175 4125);
FORCEPROP 2 LAST $XR0 164 
J 0
(-2430 4125);
DISPLAY 0.638298 (-2430 4125);
PAINT MONO (-2430 4125);
FORCEPROP 2 LAST CDS_LIB standard
J 0
(-2175 4125);
DISPLAY INVISIBLE (-2175 4125);
FORCEPROP 1 LAST OFFPAGE TRUE
J 2
(-2500 4000);
DISPLAY 0.872340 (-2500 4000);
PAINT GREEN (-2500 4000);
DISPLAY INVISIBLE (-2500 4000);
FORCEPROP 1 LAST COMMENT_BODY TRUE
J 2
(-2130 4030);
DISPLAY 0.872340 (-2130 4030);
PAINT PEACH (-2130 4030);
DISPLAY INVISIBLE (-2130 4030);
FORCEPROP 2 LAST PATH I208
J 0
(-2125 4200);
DISPLAY 1.021277 (-2125 4200);
DISPLAY INVISIBLE (-2125 4200);
FORCEADD OFFPAGE..2
R 2
(-2175 4075);
FORCEPROP 2 LAST $XR0 164 
J 0
(-2430 4075);
DISPLAY 0.638298 (-2430 4075);
PAINT MONO (-2430 4075);
FORCEPROP 2 LAST CDS_LIB standard
J 0
(-2175 4075);
DISPLAY INVISIBLE (-2175 4075);
FORCEPROP 1 LAST OFFPAGE TRUE
J 2
(-2500 3950);
DISPLAY 0.872340 (-2500 3950);
PAINT GREEN (-2500 3950);
DISPLAY INVISIBLE (-2500 3950);
FORCEPROP 1 LAST COMMENT_BODY TRUE
J 2
(-2130 3980);
DISPLAY 0.872340 (-2130 3980);
PAINT PEACH (-2130 3980);
DISPLAY INVISIBLE (-2130 3980);
FORCEPROP 2 LAST PATH I209
J 0
(-2125 4150);
DISPLAY 1.021277 (-2125 4150);
DISPLAY INVISIBLE (-2125 4150);
FORCEADD OFFPAGE..2
(-5475 2325);
FORCEPROP 2 LAST $XR0 164 
J 0
(-5286 2325);
DISPLAY 0.638298 (-5286 2325);
PAINT MONO (-5286 2325);
FORCEPROP 2 LAST CDS_LIB standard
J 0
(-5475 2325);
DISPLAY INVISIBLE (-5475 2325);
FORCEPROP 1 LAST OFFPAGE TRUE
J 0
(-5150 2200);
DISPLAY 0.872340 (-5150 2200);
PAINT GREEN (-5150 2200);
DISPLAY INVISIBLE (-5150 2200);
FORCEPROP 1 LAST COMMENT_BODY TRUE
J 0
(-5520 2230);
DISPLAY 0.872340 (-5520 2230);
PAINT PEACH (-5520 2230);
DISPLAY INVISIBLE (-5520 2230);
FORCEPROP 2 LAST PATH I210
J 0
(-5275 2375);
DISPLAY 0.680851 (-5275 2375);
DISPLAY INVISIBLE (-5275 2375);
FORCEADD Q_RES..1
R 2
(-6250 2325);
FORCEPROP 1 LAST LOCATION R1253
J 2
(-6300 2325);
DISPLAY 0.489362 (-6300 2325);
PAINT SKYBLUE (-6300 2325);
FORCEPROP 0 LAST $SEC 1
J 0
(-6300 2375);
DISPLAY 0.680851 (-6300 2375);
PAINT MONO (-6300 2375);
DISPLAY INVISIBLE (-6300 2375);
FORCEPROP 0 LAST CDS_SEC 1
J 0
(-6300 2375);
DISPLAY 0.680851 (-6300 2375);
DISPLAY INVISIBLE (-6300 2375);
FORCEPROP 1 LASTPIN (-6150 2325) $PN 1
J 2
(-6162 2337);
DISPLAY 0.489362 (-6162 2337);
PAINT MONO (-6162 2337);
FORCEPROP 1 LASTPIN (-6350 2325) $PN 2
J 2
(-6312 2337);
DISPLAY 0.489362 (-6312 2337);
PAINT MONO (-6312 2337);
FORCEPROP 1 LAST VALUE 33
J 0
(-6125 2325);
DISPLAY 0.489362 (-6125 2325);
PAINT SKYBLUE (-6125 2325);
FORCEPROP 2 LAST CDS_LIB pure_quanta
J 0
(-6250 2325);
DISPLAY INVISIBLE (-6250 2325);
FORCEPROP 2 LAST BOM_COST MEM
J 0
(-6275 2475);
DISPLAY 0.744681 (-6275 2475);
PAINT WHITE (-6275 2475);
DISPLAY INVISIBLE (-6275 2475);
FORCEPROP 1 LAST WATTAGE 1/16W
J 0
(-6175 2250);
DISPLAY 0.489362 (-6175 2250);
PAINT SKYBLUE (-6175 2250);
DISPLAY INVISIBLE (-6175 2250);
FORCEPROP 1 LAST MATERIAL CHIP
J 0
(-6425 2300);
DISPLAY 0.489362 (-6425 2300);
PAINT SKYBLUE (-6425 2300);
DISPLAY INVISIBLE (-6425 2300);
FORCEPROP 1 LAST TOLERANCE 5%
J 2
(-6125 2300);
DISPLAY 0.489362 (-6125 2300);
PAINT SKYBLUE (-6125 2300);
DISPLAY INVISIBLE (-6125 2300);
FORCEPROP 1 LAST PACK_TYPE 0402LF
J 0
(-6425 2250);
DISPLAY 0.489362 (-6425 2250);
PAINT SKYBLUE (-6425 2250);
DISPLAY INVISIBLE (-6425 2250);
FORCEPROP 1 LAST PATH I211
J 2
(-6200 2475);
DISPLAY 0.978723 (-6200 2475);
PAINT WHITE (-6200 2475);
DISPLAY INVISIBLE (-6200 2475);
FORCEPROP 1 LAST PART_NUMBER CS03302JB10
J 0
(-6350 2375);
DISPLAY 0.489362 (-6350 2375);
PAINT SKYBLUE (-6350 2375);
DISPLAY INVISIBLE (-6350 2375);
FORCEADD Q_RES..1
(-2950 1425);
FORCEPROP 1 LAST LOCATION R819
J 0
(-3125 1425);
DISPLAY 0.489362 (-3125 1425);
PAINT SKYBLUE (-3125 1425);
FORCEPROP 2 LAST $SEC 1
J 0
(-3000 1625);
DISPLAY 0.680851 (-3000 1625);
PAINT MONO (-3000 1625);
DISPLAY INVISIBLE (-3000 1625);
FORCEPROP 2 LAST CDS_SEC 1
J 0
(-3000 1625);
DISPLAY 0.680851 (-3000 1625);
DISPLAY INVISIBLE (-3000 1625);
FORCEPROP 1 LASTPIN (-3050 1425) $PN 1
J 0
(-3038 1437);
DISPLAY 0.489362 (-3038 1437);
PAINT MONO (-3038 1437);
FORCEPROP 1 LASTPIN (-2850 1425) $PN 2
J 0
(-2888 1437);
DISPLAY 0.489362 (-2888 1437);
PAINT MONO (-2888 1437);
FORCEPROP 1 LAST VALUE 0
J 2
(-2750 1425);
DISPLAY 0.489362 (-2750 1425);
PAINT SKYBLUE (-2750 1425);
FORCEPROP 1 LAST PACK_TYPE 0402LF
J 0
(-2900 1350);
DISPLAY 0.489362 (-2900 1350);
PAINT SKYBLUE (-2900 1350);
DISPLAY INVISIBLE (-2900 1350);
FORCEPROP 1 LAST TOLERANCE 5%
J 0
(-2975 1350);
DISPLAY 0.489362 (-2975 1350);
PAINT SKYBLUE (-2975 1350);
DISPLAY INVISIBLE (-2975 1350);
FORCEPROP 1 LAST MATERIAL CHIP
J 0
(-2525 1350);
DISPLAY 0.489362 (-2525 1350);
PAINT SKYBLUE (-2525 1350);
DISPLAY INVISIBLE (-2525 1350);
FORCEPROP 1 LAST WATTAGE 1/16W
J 2
(-2550 1350);
DISPLAY 0.489362 (-2550 1350);
PAINT SKYBLUE (-2550 1350);
DISPLAY INVISIBLE (-2550 1350);
FORCEPROP 2 LAST CDS_LIB pure_quanta
J 0
(-2950 1425);
DISPLAY INVISIBLE (-2950 1425);
FORCEPROP 1 LAST PATH I212
J 0
(-3000 1575);
DISPLAY 0.978723 (-3000 1575);
PAINT WHITE (-3000 1575);
DISPLAY INVISIBLE (-3000 1575);
FORCEPROP 1 LAST PART_NUMBER CS00002JB13
J 0
(-2925 1475);
DISPLAY 0.489362 (-2925 1475);
PAINT SKYBLUE (-2925 1475);
DISPLAY INVISIBLE (-2925 1475);
FORCEADD OFFPAGE..2
R 2
(-3925 1425);
FORCEPROP 2 LAST $XR0 164 
J 0
(-4210 1425);
DISPLAY 0.638298 (-4210 1425);
PAINT MONO (-4210 1425);
FORCEPROP 2 LAST CDS_LIB standard
J 0
(-3925 1425);
DISPLAY INVISIBLE (-3925 1425);
FORCEPROP 1 LAST OFFPAGE TRUE
J 2
(-4250 1300);
DISPLAY 0.872340 (-4250 1300);
PAINT GREEN (-4250 1300);
DISPLAY INVISIBLE (-4250 1300);
FORCEPROP 1 LAST COMMENT_BODY TRUE
J 2
(-3880 1330);
DISPLAY 0.872340 (-3880 1330);
PAINT PEACH (-3880 1330);
DISPLAY INVISIBLE (-3880 1330);
FORCEPROP 2 LAST PATH I213
J 0
(-3875 1500);
DISPLAY 0.680851 (-3875 1500);
DISPLAY INVISIBLE (-3875 1500);
FORCEADD Q_RES..1
(-3050 3350);
FORCEPROP 1 LAST LOCATION R818
J 0
(-3225 3350);
DISPLAY 0.489362 (-3225 3350);
PAINT SKYBLUE (-3225 3350);
FORCEPROP 2 LAST $SEC 1
J 0
(-3100 3550);
DISPLAY 0.680851 (-3100 3550);
PAINT MONO (-3100 3550);
DISPLAY INVISIBLE (-3100 3550);
FORCEPROP 2 LAST CDS_SEC 1
J 0
(-3100 3550);
DISPLAY 0.680851 (-3100 3550);
DISPLAY INVISIBLE (-3100 3550);
FORCEPROP 1 LASTPIN (-3150 3350) $PN 1
J 0
(-3138 3362);
DISPLAY 0.489362 (-3138 3362);
PAINT MONO (-3138 3362);
FORCEPROP 1 LASTPIN (-2950 3350) $PN 2
J 0
(-2988 3362);
DISPLAY 0.489362 (-2988 3362);
PAINT MONO (-2988 3362);
FORCEPROP 1 LAST VALUE 0
J 2
(-2850 3350);
DISPLAY 0.489362 (-2850 3350);
PAINT SKYBLUE (-2850 3350);
FORCEPROP 2 LAST CDS_LIB pure_quanta
J 0
(-3050 3350);
DISPLAY INVISIBLE (-3050 3350);
FORCEPROP 1 LAST WATTAGE 1/16W
J 2
(-2650 3275);
DISPLAY 0.489362 (-2650 3275);
PAINT SKYBLUE (-2650 3275);
DISPLAY INVISIBLE (-2650 3275);
FORCEPROP 1 LAST MATERIAL CHIP
J 0
(-2625 3275);
DISPLAY 0.489362 (-2625 3275);
PAINT SKYBLUE (-2625 3275);
DISPLAY INVISIBLE (-2625 3275);
FORCEPROP 1 LAST TOLERANCE 5%
J 0
(-3075 3275);
DISPLAY 0.489362 (-3075 3275);
PAINT SKYBLUE (-3075 3275);
DISPLAY INVISIBLE (-3075 3275);
FORCEPROP 1 LAST PACK_TYPE 0402LF
J 0
(-3000 3275);
DISPLAY 0.489362 (-3000 3275);
PAINT SKYBLUE (-3000 3275);
DISPLAY INVISIBLE (-3000 3275);
FORCEPROP 1 LAST PATH I220
J 0
(-3100 3500);
DISPLAY 0.978723 (-3100 3500);
PAINT WHITE (-3100 3500);
DISPLAY INVISIBLE (-3100 3500);
FORCEPROP 1 LAST PART_NUMBER CS00002JB13
J 0
(-3025 3400);
DISPLAY 0.489362 (-3025 3400);
PAINT SKYBLUE (-3025 3400);
DISPLAY INVISIBLE (-3025 3400);
FORCEADD Q_RES..1
(-3050 3450);
FORCEPROP 1 LAST LOCATION R1425
J 0
(-3275 3450);
DISPLAY 0.489362 (-3275 3450);
PAINT SKYBLUE (-3275 3450);
FORCEPROP 0 LAST $SEC 1
J 0
(-2950 3475);
DISPLAY 0.680851 (-2950 3475);
PAINT MONO (-2950 3475);
DISPLAY INVISIBLE (-2950 3475);
FORCEPROP 0 LAST CDS_SEC 1
J 0
(-2950 3475);
DISPLAY 1.021277 (-2950 3475);
DISPLAY INVISIBLE (-2950 3475);
FORCEPROP 1 LASTPIN (-3150 3450) $PN 1
J 0
(-3138 3462);
DISPLAY 0.489362 (-3138 3462);
PAINT MONO (-3138 3462);
FORCEPROP 1 LASTPIN (-2950 3450) $PN 2
J 0
(-2988 3462);
DISPLAY 0.489362 (-2988 3462);
PAINT MONO (-2988 3462);
FORCEPROP 1 LAST VALUE 0
J 2
(-2850 3450);
DISPLAY 0.489362 (-2850 3450);
PAINT SKYBLUE (-2850 3450);
FORCEPROP 2 LAST CDS_LIB pure_quanta
J 0
(-3050 3450);
DISPLAY INVISIBLE (-3050 3450);
FORCEPROP 1 LAST WATTAGE 1/16W
J 2
(-2650 3375);
DISPLAY 0.489362 (-2650 3375);
PAINT SKYBLUE (-2650 3375);
DISPLAY INVISIBLE (-2650 3375);
FORCEPROP 1 LAST MATERIAL CHIP
J 0
(-2625 3375);
DISPLAY 0.489362 (-2625 3375);
PAINT SKYBLUE (-2625 3375);
DISPLAY INVISIBLE (-2625 3375);
FORCEPROP 1 LAST TOLERANCE 5%
J 0
(-3075 3375);
DISPLAY 0.489362 (-3075 3375);
PAINT SKYBLUE (-3075 3375);
DISPLAY INVISIBLE (-3075 3375);
FORCEPROP 1 LAST PACK_TYPE 0402LF
J 0
(-3000 3375);
DISPLAY 0.489362 (-3000 3375);
PAINT SKYBLUE (-3000 3375);
DISPLAY INVISIBLE (-3000 3375);
FORCEPROP 1 LAST PATH I221
J 0
(-3100 3600);
DISPLAY 0.978723 (-3100 3600);
PAINT WHITE (-3100 3600);
DISPLAY INVISIBLE (-3100 3600);
FORCEPROP 1 LAST PART_NUMBER CS00002JB13
J 0
(-3025 3500);
DISPLAY 0.489362 (-3025 3500);
PAINT SKYBLUE (-3025 3500);
DISPLAY INVISIBLE (-3025 3500);
FORCEADD OFFPAGE..2
(-1925 3350);
FORCEPROP 2 LAST $XR0 164 
J 0
(-1736 3350);
DISPLAY 0.638298 (-1736 3350);
PAINT MONO (-1736 3350);
FORCEPROP 2 LAST CDS_LIB standard
J 0
(-1925 3350);
DISPLAY INVISIBLE (-1925 3350);
FORCEPROP 1 LAST OFFPAGE TRUE
J 0
(-1600 3225);
DISPLAY 0.872340 (-1600 3225);
PAINT GREEN (-1600 3225);
DISPLAY INVISIBLE (-1600 3225);
FORCEPROP 1 LAST COMMENT_BODY TRUE
J 0
(-1970 3255);
DISPLAY 0.872340 (-1970 3255);
PAINT PEACH (-1970 3255);
DISPLAY INVISIBLE (-1970 3255);
FORCEPROP 2 LAST PATH I222
J 0
(-1725 3400);
DISPLAY 0.680851 (-1725 3400);
DISPLAY INVISIBLE (-1725 3400);
FORCEADD OFFPAGE..1
R 2
(-1950 3400);
FORCEPROP 2 LAST $XR2 164 
J 0
(-1524 3400);
DISPLAY 0.638298 (-1524 3400);
PAINT MONO (-1524 3400);
FORCEPROP 2 LAST $XR1 151 
J 0
(-1644 3400);
DISPLAY 0.638298 (-1644 3400);
PAINT MONO (-1644 3400);
FORCEPROP 2 LAST $XR0 150 
J 0
(-1764 3400);
DISPLAY 0.638298 (-1764 3400);
PAINT MONO (-1764 3400);
FORCEPROP 2 LAST CDS_LIB standard
J 2
(-1950 3400);
DISPLAY INVISIBLE (-1950 3400);
FORCEPROP 1 LAST OFFPAGE TRUE
J 2
(-2280 3270);
PAINT GREEN (-2280 3270);
DISPLAY INVISIBLE (-2280 3270);
FORCEPROP 1 LAST COMMENT_BODY TRUE
J 2
(-2080 3300);
DISPLAY 1.106383 (-2080 3300);
PAINT PEACH (-2080 3300);
DISPLAY INVISIBLE (-2080 3300);
FORCEPROP 2 LAST PATH I223
J 0
(-1500 3450);
DISPLAY 0.680851 (-1500 3450);
DISPLAY INVISIBLE (-1500 3450);
FORCEADD OFFPAGE..2
(-1950 3450);
FORCEPROP 2 LAST $XR2 151 
J 0
(-1521 3450);
DISPLAY 0.638298 (-1521 3450);
PAINT MONO (-1521 3450);
FORCEPROP 2 LAST $XR1 150 
J 0
(-1641 3450);
DISPLAY 0.638298 (-1641 3450);
PAINT MONO (-1641 3450);
FORCEPROP 2 LAST $XR0 164 
J 0
(-1761 3450);
DISPLAY 0.638298 (-1761 3450);
PAINT MONO (-1761 3450);
FORCEPROP 2 LAST CDS_LIB standard
J 0
(-1950 3450);
DISPLAY INVISIBLE (-1950 3450);
FORCEPROP 1 LAST OFFPAGE TRUE
J 0
(-1625 3325);
DISPLAY 0.872340 (-1625 3325);
PAINT GREEN (-1625 3325);
DISPLAY INVISIBLE (-1625 3325);
FORCEPROP 1 LAST COMMENT_BODY TRUE
J 0
(-1995 3355);
DISPLAY 0.872340 (-1995 3355);
PAINT PEACH (-1995 3355);
DISPLAY INVISIBLE (-1995 3355);
FORCEPROP 2 LAST PATH I224
J 0
(-1500 3500);
DISPLAY 0.680851 (-1500 3500);
DISPLAY INVISIBLE (-1500 3500);
FORCEADD OFFPAGE..1
R 2
(-1925 3300);
FORCEPROP 2 LAST $XR0 164 
J 0
(-1739 3300);
DISPLAY 0.638298 (-1739 3300);
PAINT MONO (-1739 3300);
FORCEPROP 2 LAST CDS_LIB standard
J 0
(-1925 3300);
DISPLAY INVISIBLE (-1925 3300);
FORCEPROP 1 LAST OFFPAGE TRUE
J 2
(-2255 3170);
PAINT GREEN (-2255 3170);
DISPLAY INVISIBLE (-2255 3170);
FORCEPROP 1 LAST COMMENT_BODY TRUE
J 2
(-2055 3200);
DISPLAY 1.106383 (-2055 3200);
PAINT PEACH (-2055 3200);
DISPLAY INVISIBLE (-2055 3200);
FORCEPROP 2 LAST PATH I225
J 0
(-1725 3350);
DISPLAY 0.680851 (-1725 3350);
DISPLAY INVISIBLE (-1725 3350);
FORCEADD UNIVERSAL_GND..1
R 2
(-3925 2700);
FORCEPROP 3 LASTPIN (-3925 2750) SIG_NAME GND\g
J 0
(-3915 2760);
DISPLAY 0.659574 (-3915 2760);
PAINT MONO (-3915 2760);
DISPLAY INVISIBLE (-3915 2760);
FORCEPROP 2 LAST CDS_LIB pure_quanta_power
J 0
(-3925 2700);
DISPLAY INVISIBLE (-3925 2700);
FORCEPROP 1 LAST HDL_POWER GND
J 1
(-3950 2625);
DISPLAY 0.702128 (-3950 2625);
PAINT GREEN (-3950 2625);
DISPLAY INVISIBLE (-3950 2625);
FORCEPROP 1 LAST PATH I226
J 2
(-4000 2700);
DISPLAY 0.872340 (-4000 2700);
PAINT AQUA (-4000 2700);
DISPLAY INVISIBLE (-4000 2700);
FORCEADD OFFPAGE..2
R 2
(-6700 3300);
FORCEPROP 2 LAST $XR1 27 
J 0
(-7045 3300);
DISPLAY 0.638298 (-7045 3300);
PAINT MONO (-7045 3300);
FORCEPROP 2 LAST $XR0 164 
J 0
(-6955 3300);
DISPLAY 0.638298 (-6955 3300);
PAINT MONO (-6955 3300);
FORCEPROP 2 LAST CDS_LIB standard
J 0
(-6700 3300);
DISPLAY INVISIBLE (-6700 3300);
FORCEPROP 1 LAST OFFPAGE TRUE
J 2
(-7025 3175);
DISPLAY 0.872340 (-7025 3175);
PAINT GREEN (-7025 3175);
DISPLAY INVISIBLE (-7025 3175);
FORCEPROP 1 LAST COMMENT_BODY TRUE
J 2
(-6655 3205);
DISPLAY 0.872340 (-6655 3205);
PAINT PEACH (-6655 3205);
DISPLAY INVISIBLE (-6655 3205);
FORCEPROP 2 LAST PATH I227
J 0
(-6950 3350);
DISPLAY 0.680851 (-6950 3350);
DISPLAY INVISIBLE (-6950 3350);
FORCEADD OFFPAGE..1
(-6700 3350);
FORCEPROP 2 LAST $XR1 164 
J 0
(-7071 3350);
DISPLAY 0.638298 (-7071 3350);
PAINT MONO (-7071 3350);
FORCEPROP 2 LAST $XR0 27 
J 0
(-6951 3350);
DISPLAY 0.638298 (-6951 3350);
PAINT MONO (-6951 3350);
FORCEPROP 2 LAST CDS_LIB standard
J 0
(-6700 3350);
DISPLAY INVISIBLE (-6700 3350);
FORCEPROP 1 LAST OFFPAGE TRUE
J 0
(-6370 3220);
PAINT GREEN (-6370 3220);
DISPLAY INVISIBLE (-6370 3220);
FORCEPROP 1 LAST COMMENT_BODY TRUE
J 0
(-6570 3250);
DISPLAY 1.106383 (-6570 3250);
PAINT PEACH (-6570 3250);
DISPLAY INVISIBLE (-6570 3250);
FORCEPROP 2 LAST PATH I228
J 0
(-6950 3400);
DISPLAY 0.680851 (-6950 3400);
DISPLAY INVISIBLE (-6950 3400);
FORCEADD OFFPAGE..2
R 2
(-6700 3400);
FORCEPROP 2 LAST $XR1 27 
J 0
(-7045 3400);
DISPLAY 0.638298 (-7045 3400);
PAINT MONO (-7045 3400);
FORCEPROP 2 LAST $XR0 164 
J 0
(-6955 3400);
DISPLAY 0.638298 (-6955 3400);
PAINT MONO (-6955 3400);
FORCEPROP 2 LAST CDS_LIB standard
J 2
(-6700 3400);
DISPLAY INVISIBLE (-6700 3400);
FORCEPROP 1 LAST OFFPAGE TRUE
J 2
(-7025 3275);
DISPLAY 0.872340 (-7025 3275);
PAINT GREEN (-7025 3275);
DISPLAY INVISIBLE (-7025 3275);
FORCEPROP 1 LAST COMMENT_BODY TRUE
J 2
(-6655 3305);
DISPLAY 0.872340 (-6655 3305);
PAINT PEACH (-6655 3305);
DISPLAY INVISIBLE (-6655 3305);
FORCEPROP 2 LAST PATH I229
J 0
(-6950 3450);
DISPLAY 0.680851 (-6950 3450);
DISPLAY INVISIBLE (-6950 3450);
FORCEADD OFFPAGE..1
(-6700 3450);
FORCEPROP 2 LAST $XR2 164 
J 0
(-7161 3450);
DISPLAY 0.638298 (-7161 3450);
PAINT MONO (-7161 3450);
FORCEPROP 2 LAST $XR1 76 
J 0
(-7041 3450);
DISPLAY 0.638298 (-7041 3450);
PAINT MONO (-7041 3450);
FORCEPROP 2 LAST $XR0 27 
J 0
(-6951 3450);
DISPLAY 0.638298 (-6951 3450);
PAINT MONO (-6951 3450);
FORCEPROP 2 LAST CDS_LIB standard
J 0
(-6700 3450);
DISPLAY INVISIBLE (-6700 3450);
FORCEPROP 1 LAST OFFPAGE TRUE
J 0
(-6370 3320);
PAINT GREEN (-6370 3320);
DISPLAY INVISIBLE (-6370 3320);
FORCEPROP 1 LAST COMMENT_BODY TRUE
J 0
(-6570 3350);
DISPLAY 1.106383 (-6570 3350);
PAINT PEACH (-6570 3350);
DISPLAY INVISIBLE (-6570 3350);
FORCEPROP 2 LAST PATH I230
J 0
(-6950 3500);
DISPLAY 0.680851 (-6950 3500);
DISPLAY INVISIBLE (-6950 3500);
FORCEADD Q_RES..1
(-5825 3300);
FORCEPROP 1 LAST LOCATION R817
J 0
(-6025 3300);
DISPLAY 0.489362 (-6025 3300);
PAINT SKYBLUE (-6025 3300);
FORCEPROP 2 LAST $SEC 1
J 0
(-5875 3500);
DISPLAY 0.680851 (-5875 3500);
PAINT MONO (-5875 3500);
DISPLAY INVISIBLE (-5875 3500);
FORCEPROP 2 LAST CDS_SEC 1
J 0
(-5875 3500);
DISPLAY 0.680851 (-5875 3500);
DISPLAY INVISIBLE (-5875 3500);
FORCEPROP 1 LASTPIN (-5925 3300) $PN 1
J 0
(-5913 3312);
DISPLAY 0.489362 (-5913 3312);
PAINT MONO (-5913 3312);
FORCEPROP 1 LASTPIN (-5725 3300) $PN 2
J 0
(-5763 3312);
DISPLAY 0.489362 (-5763 3312);
PAINT MONO (-5763 3312);
FORCEPROP 1 LAST VALUE 0
J 2
(-5675 3300);
DISPLAY 0.489362 (-5675 3300);
PAINT SKYBLUE (-5675 3300);
FORCEPROP 2 LAST CDS_LIB pure_quanta
J 0
(-5825 3300);
DISPLAY INVISIBLE (-5825 3300);
FORCEPROP 1 LAST WATTAGE 1/16W
J 2
(-5425 3225);
DISPLAY 0.489362 (-5425 3225);
PAINT SKYBLUE (-5425 3225);
DISPLAY INVISIBLE (-5425 3225);
FORCEPROP 1 LAST MATERIAL CHIP
J 0
(-5400 3225);
DISPLAY 0.489362 (-5400 3225);
PAINT SKYBLUE (-5400 3225);
DISPLAY INVISIBLE (-5400 3225);
FORCEPROP 1 LAST TOLERANCE 5%
J 0
(-5850 3225);
DISPLAY 0.489362 (-5850 3225);
PAINT SKYBLUE (-5850 3225);
DISPLAY INVISIBLE (-5850 3225);
FORCEPROP 1 LAST PACK_TYPE 0402LF
J 0
(-5775 3225);
DISPLAY 0.489362 (-5775 3225);
PAINT SKYBLUE (-5775 3225);
DISPLAY INVISIBLE (-5775 3225);
FORCEPROP 1 LAST PATH I231
J 0
(-5875 3450);
DISPLAY 0.978723 (-5875 3450);
PAINT WHITE (-5875 3450);
DISPLAY INVISIBLE (-5875 3450);
FORCEPROP 1 LAST PART_NUMBER CS00002JB13
J 0
(-5800 3350);
DISPLAY 0.489362 (-5800 3350);
PAINT SKYBLUE (-5800 3350);
DISPLAY INVISIBLE (-5800 3350);
FORCEADD Q_RES..1
(-5825 3400);
FORCEPROP 1 LAST LOCATION R1423
J 0
(-6025 3400);
DISPLAY 0.489362 (-6025 3400);
PAINT SKYBLUE (-6025 3400);
FORCEPROP 0 LAST $SEC 1
J 0
(-5700 3450);
DISPLAY 0.680851 (-5700 3450);
PAINT MONO (-5700 3450);
DISPLAY INVISIBLE (-5700 3450);
FORCEPROP 0 LAST CDS_SEC 1
J 0
(-5700 3450);
DISPLAY 1.021277 (-5700 3450);
DISPLAY INVISIBLE (-5700 3450);
FORCEPROP 1 LASTPIN (-5925 3400) $PN 1
J 0
(-5913 3412);
DISPLAY 0.489362 (-5913 3412);
PAINT MONO (-5913 3412);
FORCEPROP 1 LASTPIN (-5725 3400) $PN 2
J 0
(-5763 3412);
DISPLAY 0.489362 (-5763 3412);
PAINT MONO (-5763 3412);
FORCEPROP 1 LAST VALUE 0
J 2
(-5675 3400);
DISPLAY 0.489362 (-5675 3400);
PAINT SKYBLUE (-5675 3400);
FORCEPROP 2 LAST CDS_LIB pure_quanta
J 0
(-5825 3400);
DISPLAY INVISIBLE (-5825 3400);
FORCEPROP 1 LAST WATTAGE 1/16W
J 2
(-5425 3325);
DISPLAY 0.489362 (-5425 3325);
PAINT SKYBLUE (-5425 3325);
DISPLAY INVISIBLE (-5425 3325);
FORCEPROP 1 LAST MATERIAL CHIP
J 0
(-5400 3325);
DISPLAY 0.489362 (-5400 3325);
PAINT SKYBLUE (-5400 3325);
DISPLAY INVISIBLE (-5400 3325);
FORCEPROP 1 LAST TOLERANCE 5%
J 0
(-5850 3325);
DISPLAY 0.489362 (-5850 3325);
PAINT SKYBLUE (-5850 3325);
DISPLAY INVISIBLE (-5850 3325);
FORCEPROP 1 LAST PACK_TYPE 0402LF
J 0
(-5775 3325);
DISPLAY 0.489362 (-5775 3325);
PAINT SKYBLUE (-5775 3325);
DISPLAY INVISIBLE (-5775 3325);
FORCEPROP 1 LAST PATH I232
J 0
(-5875 3550);
DISPLAY 0.978723 (-5875 3550);
PAINT WHITE (-5875 3550);
DISPLAY INVISIBLE (-5875 3550);
FORCEPROP 1 LAST PART_NUMBER CS00002JB13
J 0
(-5800 3450);
DISPLAY 0.489362 (-5800 3450);
PAINT SKYBLUE (-5800 3450);
DISPLAY INVISIBLE (-5800 3450);
FORCEADD OFFPAGE..1
(-5900 2950);
FORCEPROP 2 LAST $XR0 164 
J 0
(-6182 2950);
DISPLAY 0.638298 (-6182 2950);
PAINT MONO (-6182 2950);
FORCEPROP 2 LAST CDS_LIB standard
J 0
(-5900 2950);
DISPLAY INVISIBLE (-5900 2950);
FORCEPROP 1 LAST OFFPAGE TRUE
J 0
(-5570 2820);
PAINT GREEN (-5570 2820);
DISPLAY INVISIBLE (-5570 2820);
FORCEPROP 1 LAST COMMENT_BODY TRUE
J 0
(-5770 2850);
DISPLAY 1.106383 (-5770 2850);
PAINT PEACH (-5770 2850);
DISPLAY INVISIBLE (-5770 2850);
FORCEPROP 2 LAST PATH I233
J 0
(-6150 3000);
DISPLAY 0.680851 (-6150 3000);
DISPLAY INVISIBLE (-6150 3000);
FORCEADD UNIVERSAL_GND..1
R 5
(-5250 3000);
FORCEPROP 3 LASTPIN (-5200 3000) SIG_NAME GND\g
J 0
(-5190 3010);
DISPLAY 0.659574 (-5190 3010);
PAINT MONO (-5190 3010);
DISPLAY INVISIBLE (-5190 3010);
FORCEPROP 2 LAST CDS_LIB pure_quanta_power
R 3
J 2
(-5250 3000);
DISPLAY INVISIBLE (-5250 3000);
FORCEPROP 1 LAST HDL_POWER GND
R 3
J 1
(-5325 2975);
DISPLAY 0.702128 (-5325 2975);
PAINT GREEN (-5325 2975);
DISPLAY INVISIBLE (-5325 2975);
FORCEPROP 1 LAST PATH I234
R 3
J 0
(-5250 2925);
DISPLAY 0.872340 (-5250 2925);
PAINT AQUA (-5250 2925);
DISPLAY INVISIBLE (-5250 2925);
FORCEADD UNIVERSAL_GND..1
R 5
(-5250 3100);
FORCEPROP 3 LASTPIN (-5200 3100) SIG_NAME GND\g
J 0
(-5190 3110);
DISPLAY 0.659574 (-5190 3110);
PAINT MONO (-5190 3110);
DISPLAY INVISIBLE (-5190 3110);
FORCEPROP 2 LAST CDS_LIB pure_quanta_power
R 3
J 2
(-5250 3100);
DISPLAY INVISIBLE (-5250 3100);
FORCEPROP 1 LAST HDL_POWER GND
R 3
J 1
(-5325 3075);
DISPLAY 0.702128 (-5325 3075);
PAINT GREEN (-5325 3075);
DISPLAY INVISIBLE (-5325 3075);
FORCEPROP 1 LAST PATH I235
R 3
J 0
(-5250 3025);
DISPLAY 0.872340 (-5250 3025);
PAINT AQUA (-5250 3025);
DISPLAY INVISIBLE (-5250 3025);
FORCEADD UNIVERSAL_POWER..1
(-6100 3175);
FORCEPROP 3 LASTPIN (-6100 3125) SIG_NAME PVDD18_S5_P0\g
J 0
(-6090 3135);
DISPLAY 0.659574 (-6090 3135);
PAINT MONO (-6090 3135);
DISPLAY INVISIBLE (-6090 3135);
FORCEPROP 1 LAST HDL_POWER PVDD18_S5_P0
J 1
(-6100 3225);
DISPLAY 0.489362 (-6100 3225);
PAINT GREEN (-6100 3225);
FORCEPROP 2 LAST CDS_LIB pure_quanta_power
J 0
(-6100 3175);
DISPLAY INVISIBLE (-6100 3175);
FORCEPROP 1 LAST PATH I236
J 0
(-6050 3200);
DISPLAY 0.872340 (-6050 3200);
PAINT AQUA (-6050 3200);
DISPLAY INVISIBLE (-6050 3200);
FORCEADD OFFPAGE..1
(-7725 1975);
FORCEPROP 2 LAST $XR0 81 
J 0
(-7946 1975);
DISPLAY 0.638298 (-7946 1975);
PAINT MONO (-7946 1975);
FORCEPROP 2 LAST CDS_LIB standard
J 0
(-7725 1975);
DISPLAY INVISIBLE (-7725 1975);
FORCEPROP 1 LAST OFFPAGE TRUE
J 0
(-7395 1845);
PAINT GREEN (-7395 1845);
DISPLAY INVISIBLE (-7395 1845);
FORCEPROP 1 LAST COMMENT_BODY TRUE
J 0
(-7595 1875);
DISPLAY 1.106383 (-7595 1875);
PAINT PEACH (-7595 1875);
DISPLAY INVISIBLE (-7595 1875);
FORCEPROP 2 LAST PATH I88
J 0
(-7975 2025);
DISPLAY 1.021277 (-7975 2025);
DISPLAY INVISIBLE (-7975 2025);
FORCEADD MOSFET_N_GSD..1
(-6900 2025);
FORCEPROP 1 LAST LOCATION Q61
J 0
(-6799 2070);
DISPLAY 0.489362 (-6799 2070);
PAINT SKYBLUE (-6799 2070);
FORCEPROP 0 LAST $SEC 1
J 0
(-6800 2250);
DISPLAY 0.680851 (-6800 2250);
PAINT MONO (-6800 2250);
DISPLAY INVISIBLE (-6800 2250);
FORCEPROP 0 LAST CDS_SEC 1
J 0
(-6800 2250);
DISPLAY 1.021277 (-6800 2250);
DISPLAY INVISIBLE (-6800 2250);
FORCEPROP 0 LASTPIN (-6875 2175) $PN D
R 1
J 0
(-6885 2185);
DISPLAY 0.489362 (-6885 2185);
PAINT MONO (-6885 2185);
FORCEPROP 0 LASTPIN (-7075 1975) $PN G
J 2
(-7085 1985);
DISPLAY 0.489362 (-7085 1985);
PAINT MONO (-7085 1985);
FORCEPROP 0 LASTPIN (-6875 1875) $PN S
R 1
J 2
(-6885 1865);
DISPLAY 0.489362 (-6885 1865);
PAINT MONO (-6885 1865);
FORCEPROP 1 LAST MATERIAL IC
J 0
(-6799 1925);
DISPLAY 0.489362 (-6799 1925);
PAINT SKYBLUE (-6799 1925);
FORCEPROP 2 LAST PART_TYPE SMLF
J 0
(-6800 2200);
DISPLAY 1.021277 (-6800 2200);
FORCEPROP 2 LAST VALUE NX138BK
J 0
(-6800 2150);
DISPLAY 0.489362 (-6800 2150);
PAINT SKYBLUE (-6800 2150);
FORCEPROP 2 LAST CDS_LIB pure_quanta
J 0
(-6900 2025);
DISPLAY INVISIBLE (-6900 2025);
FORCEPROP 1 LAST CDS_LMAN_SYM_OUTLINE -100,100,100,-100
J 0
(-6900 2025);
DISPLAY 0.468085 (-6900 2025);
PAINT GREEN (-6900 2025);
DISPLAY INVISIBLE (-6900 2025);
FORCEPROP 1 LAST NEEDS_NO_SIZE TRUE
J 0
(-6900 2025);
DISPLAY 0.468085 (-6900 2025);
PAINT GREEN (-6900 2025);
DISPLAY INVISIBLE (-6900 2025);
FORCEPROP 1 LAST PATH I89
J 0
(-6900 2025);
DISPLAY 0.723404 (-6900 2025);
PAINT GREEN (-6900 2025);
DISPLAY INVISIBLE (-6900 2025);
FORCEPROP 1 LAST PART_NUMBER BAM01380023
J 0
(-6799 2005);
DISPLAY 0.489362 (-6799 2005);
PAINT SKYBLUE (-6799 2005);
DISPLAY INVISIBLE (-6799 2005);
FORCEADD UNIVERSAL_GND..1
R 2
(-6875 1675);
FORCEPROP 3 LASTPIN (-6875 1725) SIG_NAME GND\g
J 0
(-6865 1735);
DISPLAY 0.659574 (-6865 1735);
PAINT MONO (-6865 1735);
DISPLAY INVISIBLE (-6865 1735);
FORCEPROP 2 LAST CDS_LIB pure_quanta_power
J 0
(-6875 1675);
DISPLAY INVISIBLE (-6875 1675);
FORCEPROP 1 LAST HDL_POWER GND
J 1
(-6900 1600);
DISPLAY 0.702128 (-6900 1600);
PAINT GREEN (-6900 1600);
DISPLAY INVISIBLE (-6900 1600);
FORCEPROP 1 LAST PATH I90
J 2
(-6950 1675);
DISPLAY 0.872340 (-6950 1675);
PAINT AQUA (-6950 1675);
DISPLAY INVISIBLE (-6950 1675);
FORCEADD Q_RES..2
(-6875 2550);
FORCEPROP 1 LAST LOCATION R1419
J 0
(-6830 2675);
DISPLAY 0.489362 (-6830 2675);
PAINT SKYBLUE (-6830 2675);
FORCEPROP 0 LAST $SEC 1
J 0
(-6825 2700);
DISPLAY 0.680851 (-6825 2700);
PAINT MONO (-6825 2700);
DISPLAY INVISIBLE (-6825 2700);
FORCEPROP 0 LAST CDS_SEC 1
J 0
(-6825 2700);
DISPLAY 1.021277 (-6825 2700);
DISPLAY INVISIBLE (-6825 2700);
FORCEPROP 1 LASTPIN (-6875 2650) $PN 1
J 0
(-6870 2612);
DISPLAY 0.489362 (-6870 2612);
PAINT MONO (-6870 2612);
FORCEPROP 1 LASTPIN (-6875 2450) $PN 2
J 0
(-6870 2460);
DISPLAY 0.489362 (-6870 2460);
PAINT MONO (-6870 2460);
FORCEPROP 1 LAST TOLERANCE 5%
J 0
(-6830 2575);
DISPLAY 0.489362 (-6830 2575);
PAINT SKYBLUE (-6830 2575);
FORCEPROP 1 LAST PACK_TYPE 0402LF
J 0
(-6825 2425);
DISPLAY 0.489362 (-6825 2425);
PAINT SKYBLUE (-6825 2425);
FORCEPROP 1 LAST MATERIAL CHIP
J 0
(-6835 2475);
DISPLAY 0.489362 (-6835 2475);
PAINT SKYBLUE (-6835 2475);
FORCEPROP 1 LAST WATTAGE 1/16W
J 0
(-6835 2525);
DISPLAY 0.489362 (-6835 2525);
PAINT SKYBLUE (-6835 2525);
FORCEPROP 1 LAST VALUE 4.7K
J 0
(-6830 2625);
DISPLAY 0.489362 (-6830 2625);
PAINT SKYBLUE (-6830 2625);
FORCEPROP 2 LAST CDS_LIB pure_quanta
J 0
(-6875 2550);
DISPLAY INVISIBLE (-6875 2550);
FORCEPROP 1 LAST PATH I91
J 0
(-6825 2725);
DISPLAY 0.978723 (-6825 2725);
PAINT WHITE (-6825 2725);
DISPLAY INVISIBLE (-6825 2725);
FORCEPROP 1 LAST PART_NUMBER CS24702JB10
J 0
(-6835 2425);
DISPLAY 0.489362 (-6835 2425);
PAINT SKYBLUE (-6835 2425);
DISPLAY INVISIBLE (-6835 2425);
FORCEADD DNS..2
(-2300 1075);
PAINT RED (-2300 1075);
FORCEPROP 2 LAST CDS_LIB mstr_misc
J 0
(-2300 1075);
DISPLAY INVISIBLE (-2300 1075);
FORCEPROP 1 LAST COMMENT_BODY TRUE
R 1
J 0
(-2225 850);
DISPLAY 0.872340 (-2225 850);
PAINT PEACH (-2225 850);
DISPLAY INVISIBLE (-2225 850);
FORCEADD QUANTA_TITLE_BLOCK_C..1
(0 0);
FORCEPROP 0 LAST CDS_CON_LAST_MODIFIED Thu Sep 14 16:12:15 2023
J 0
(-1885 15);
DISPLAY INVISIBLE (-1885 15);
FORCEPROP 1 LAST CUSTOM_TXT_CDS <CON_LAST_MODIFIED>
J 0
(-1885 15);
DISPLAY 0.978723 (-1885 15);
FORCEPROP 2 LAST CUSTOM_TXT_CDS <XR_PAGE_TITLE>
J 0
(-7890 5250);
DISPLAY 0.638298 (-7890 5250);
PAINT PINK (-7890 5250);
DISPLAY INVISIBLE (-7890 5250);
FORCEPROP 1 LAST CUSTOM_TXT_CDS <NAME_2>
J 0
(-3175 50);
FORCEPROP 1 LAST CUSTOM_TXT_CDS <NAME_1>
J 0
(-3175 175);
FORCEPROP 1 LAST CUSTOM_TXT_CDS <Q_NUMBER>
J 0
(-1403 103);
DISPLAY 1.212766 (-1403 103);
FORCEPROP 1 LAST CUSTOM_TXT_CDS <Q_PROJ>
J 0
(-2382 102);
DISPLAY 1.212766 (-2382 102);
FORCEPROP 1 LAST CUSTOM_TXT_CDS <Q_REV>
J 0
(-184 103);
DISPLAY 1.212766 (-184 103);
FORCEPROP 1 LAST CUSTOM_TXT_CDS <CON_PAGE_NUM> OF <CON_TOTAL_PAGES>
J 0
(-446 18);
DISPLAY 0.978723 (-446 18);
FORCEPROP 1 LAST Q_TITLE UART LEVEL SHIFT
J 0
(-9300 50);
DISPLAY 2.446809 (-9300 50);
PAINT GREEN (-9300 50);
FORCEPROP 2 LAST PAGE_BORDER TRUE
J 0
(-7890 5250);
DISPLAY 0.638298 (-7890 5250);
PAINT PINK (-7890 5250);
DISPLAY INVISIBLE (-7890 5250);
FORCEPROP 2 LAST CDS_LIB pure_quanta
J 0
(0 0);
DISPLAY INVISIBLE (0 0);
FORCEPROP 1 LAST CDS_LMAN_SYM_OUTLINE -9475,6775,100,-125
J 0
(0 0);
DISPLAY 0.468085 (0 0);
PAINT GREEN (0 0);
DISPLAY INVISIBLE (0 0);
FORCEPROP 2 LAST CDS_XR_PAGE_TITLE CR-164 : @T6G_MB_LIB.T6G(SCH_1):PAGE164
J 0
(-7890 5250);
DISPLAY 0.638298 (-7890 5250);
PAINT PINK (-7890 5250);
DISPLAY INVISIBLE (-7890 5250);
FORCEPROP 1 LAST Q_DEPT BU9
J 1
(-3763 49);
DISPLAY 1.957447 (-3763 49);
PAINT GREEN (-3763 49);
DISPLAY INVISIBLE (-3763 49);
FORCEPROP 1 LAST COMMENT_BODY TRUE
J 0
(12 -13);
DISPLAY 0.978723 (12 -13);
PAINT GREEN (12 -13);
DISPLAY INVISIBLE (12 -13);
FORCEADD DNS..2
(-1025 4425);
PAINT RED (-1025 4425);
FORCEPROP 2 LAST CDS_LIB mstr_misc
J 0
(-1025 4425);
DISPLAY INVISIBLE (-1025 4425);
FORCEPROP 1 LAST COMMENT_BODY TRUE
J 0
(-1025 4425);
PAINT RED (-1025 4425);
DISPLAY INVISIBLE (-1025 4425);
FORCEADD DNS..2
(-600 4425);
PAINT RED (-600 4425);
FORCEPROP 2 LAST CDS_LIB mstr_misc
J 0
(-600 4425);
DISPLAY INVISIBLE (-600 4425);
FORCEPROP 1 LAST COMMENT_BODY TRUE
J 0
(-600 4425);
PAINT RED (-600 4425);
DISPLAY INVISIBLE (-600 4425);
FORCEADD DNS..2
(-7600 4125);
PAINT RED (-7600 4125);
FORCEPROP 2 LAST CDS_LIB mstr_misc
J 0
(-7600 4125);
DISPLAY INVISIBLE (-7600 4125);
FORCEPROP 1 LAST COMMENT_BODY TRUE
J 0
(-7600 4125);
PAINT RED (-7600 4125);
DISPLAY INVISIBLE (-7600 4125);
FORCEADD DNS..2
(-7825 4125);
PAINT RED (-7825 4125);
FORCEPROP 2 LAST CDS_LIB mstr_misc
J 0
(-7825 4125);
DISPLAY INVISIBLE (-7825 4125);
FORCEPROP 1 LAST COMMENT_BODY TRUE
J 0
(-7825 4125);
PAINT RED (-7825 4125);
DISPLAY INVISIBLE (-7825 4125);
WIRE 16 -1 (-3850 3575)(-3850 3625);
WIRE 16 -1 (-5175 3575)(-5175 3625);
WIRE 16 -1 (-6875 2650)(-6875 2700);
WIRE 16 -1 (-1975 1525)(-1550 1525);
WIRE 16 -1 (-1975 1525)(-1975 1225);
WIRE 16 -1 (-2150 1275)(-2150 1175);
WIRE 16 -1 (-2375 1200)(-2375 1275);
WIRE 16 -1 (-2575 1050)(-2575 1000);
WIRE 16 -1 (-2775 1050)(-2775 1000);
WIRE 16 -1 (-4125 2900)(-3925 2900);
WIRE 16 -1 (-3925 2900)(-3925 2750);
WIRE 16 -1 (-4925 3000)(-5200 3000);
WIRE 16 -1 (-4925 3100)(-5200 3100);
WIRE 16 -1 (-6875 1875)(-6875 1725);
WIRE 16 -1 (-5525 2325)(-6150 2325);
FORCEPROP 2 LAST SIG_NAME UART_LS_EN_N
J 0
(-5935 2335);
DISPLAY 0.489362 (-5935 2335);
WIRE 16 -1 (-6350 2325)(-6875 2325);
FORCEPROP 2 LAST SIG_NAME UART_LS_EN_R_N
J 0
(-6785 2335);
DISPLAY 0.489362 (-6785 2335);
FORCEPROP 2 LASTPROP $XRERR UNIQUE?
J 0
(-7025 2335);
DISPLAY 0.638298 (-7025 2335);
PAINT MONO (-7025 2335);
DISPLAY INVISIBLE (-7025 2335);
WIRE 16 -1 (-6875 2325)(-6875 2450);
WIRE 16 -1 (-6875 2175)(-6875 2325);
WIRE 16 -1 (-825 4325)(-825 4125);
WIRE 16 -1 (-2125 4125)(-825 4125);
FORCEPROP 2 LAST SIG_NAME UART_CPU0_LVC3_UART0_TX
J 0
(-2060 4135);
DISPLAY 0.489362 (-2060 4135);
WIRE 16 -1 (-1050 4625)(-825 4625);
WIRE 16 -1 (-1250 4625)(-1050 4625);
WIRE 16 -1 (-1050 4625)(-1050 4525);
WIRE 16 -1 (-625 4625)(-825 4625);
WIRE 16 -1 (-825 4625)(-825 4525);
WIRE 16 -1 (-625 4625)(-625 4525);
WIRE 16 -1 (-1250 4525)(-1250 4625);
WIRE 16 -1 (-1250 4625)(-1250 4650);
WIRE 16 -1 (-8050 4025)(-8050 3750);
WIRE 16 -1 (-6350 3750)(-8050 3750);
FORCEPROP 2 LAST SIG_NAME UART_CPU0_UART0_RX
J 0
(-7275 3760);
DISPLAY 0.489362 (-7275 3760);
WIRE 16 -1 (-8050 4225)(-8050 4350);
WIRE 16 -1 (-8050 4350)(-7850 4350);
WIRE 16 -1 (-7850 4350)(-7625 4350);
WIRE 16 -1 (-7850 4225)(-7850 4350);
WIRE 16 -1 (-7625 4350)(-7425 4350);
WIRE 16 -1 (-7625 4225)(-7625 4350);
WIRE 16 -1 (-7425 4350)(-7425 4375);
WIRE 16 -1 (-7425 4225)(-7425 4350);
WIRE 16 -1 (-1250 4225)(-1250 4325);
WIRE 16 -1 (-1250 4225)(-2125 4225);
FORCEPROP 2 LAST SIG_NAME UART_CPU0_SCM_LVC3_UART1_TX
J 0
(-2060 4235);
DISPLAY 0.489362 (-2060 4235);
WIRE 16 -1 (-7425 4025)(-7425 3950);
WIRE 16 -1 (-7425 3950)(-6350 3950);
FORCEPROP 2 LAST SIG_NAME UART_CPU0_SCM_UART1_RX
J 0
(-7275 3960);
DISPLAY 0.489362 (-7275 3960);
WIRE 16 -1 (-2375 1000)(-2375 950);
WIRE 16 -1 (-2375 950)(-2150 950);
WIRE 16 -1 (-1700 950)(-2150 950);
FORCEPROP 2 LAST SIG_NAME UART_VCC_J13
J 0
(-2085 960);
DISPLAY 0.489362 (-2085 960);
FORCEPROP 2 LASTPROP $XRERR UNIQUE?
J 0
(-2325 960);
DISPLAY 0.638298 (-2325 960);
PAINT MONO (-2325 960);
DISPLAY INVISIBLE (-2325 960);
WIRE 16 -1 (-2150 975)(-2150 950);
WIRE 16 -1 (-1700 1375)(-1700 950);
WIRE 16 -1 (-1700 1375)(-1550 1375);
WIRE 16 -1 (-1050 4325)(-1050 4175);
WIRE 16 -1 (-1050 4175)(-2125 4175);
FORCEPROP 2 LAST SIG_NAME UART_CPU0_SCM_LVC3_UART1_R_RX
J 0
(-2060 4185);
DISPLAY 0.489362 (-2060 4185);
WIRE 16 -1 (-625 4325)(-625 4075);
WIRE 16 -1 (-2125 4075)(-625 4075);
FORCEPROP 2 LAST SIG_NAME UART_CPU0_LVC3_UART0_RX
J 0
(-2060 4085);
DISPLAY 0.489362 (-2060 4085);
WIRE 16 -1 (-7850 4025)(-7850 3800);
WIRE 16 -1 (-6350 3800)(-7850 3800);
FORCEPROP 2 LAST SIG_NAME UART_CPU0_UART0_TX
J 0
(-7275 3810);
DISPLAY 0.489362 (-7275 3810);
WIRE 16 -1 (-7625 4025)(-7625 3875);
WIRE 16 -1 (-6350 3875)(-7625 3875);
FORCEPROP 2 LAST SIG_NAME UART_CPU0_SCM_UART1_TX
J 0
(-7275 3885);
DISPLAY 0.489362 (-7275 3885);
WIRE 16 -1 (-6650 3400)(-5925 3400);
FORCEPROP 2 LAST SIG_NAME UART_CPU0_SCM_UART1_RX
J 0
(-6625 3410);
DISPLAY 0.489362 (-6625 3410);
WIRE 16 -1 (-5725 3400)(-4925 3400);
FORCEPROP 2 LAST SIG_NAME UART_CPU0_SCM_UART1_R_RX
J 0
(-5585 3410);
DISPLAY 0.489362 (-5585 3410);
FORCEPROP 2 LASTPROP $XRERR UNIQUE?
J 0
(-5825 3410);
DISPLAY 0.638298 (-5825 3410);
PAINT MONO (-5825 3410);
DISPLAY INVISIBLE (-5825 3410);
WIRE 16 -1 (-5925 3300)(-6650 3300);
FORCEPROP 2 LAST SIG_NAME UART_CPU0_UART0_RX
J 0
(-6625 3310);
DISPLAY 0.489362 (-6625 3310);
WIRE 16 -1 (-5725 3300)(-4925 3300);
FORCEPROP 2 LAST SIG_NAME UART_CPU0_UART0_R_RX
J 0
(-5560 3310);
DISPLAY 0.489362 (-5560 3310);
FORCEPROP 2 LASTPROP $XRERR UNIQUE?
J 0
(-5800 3310);
DISPLAY 0.638298 (-5800 3310);
PAINT MONO (-5800 3310);
DISPLAY INVISIBLE (-5800 3310);
WIRE 16 -1 (-4125 3450)(-3150 3450);
FORCEPROP 2 LAST SIG_NAME UART_CPU0_SCM_LVC3_UART1_R_TX
J 0
(-3985 3460);
DISPLAY 0.489362 (-3985 3460);
FORCEPROP 2 LASTPROP $XRERR UNIQUE?
J 0
(-4225 3460);
DISPLAY 0.638298 (-4225 3460);
PAINT MONO (-4225 3460);
DISPLAY INVISIBLE (-4225 3460);
WIRE 16 -1 (-2950 3450)(-2000 3450);
FORCEPROP 2 LAST SIG_NAME UART_CPU0_SCM_LVC3_UART1_TX
J 0
(-2725 3460);
DISPLAY 0.489362 (-2725 3460);
WIRE 16 -1 (-4125 3350)(-3150 3350);
FORCEPROP 2 LAST SIG_NAME UART_CPU0_LVC3_UART0_R_TX
J 0
(-3985 3360);
DISPLAY 0.489362 (-3985 3360);
FORCEPROP 2 LASTPROP $XRERR UNIQUE?
J 0
(-4225 3360);
DISPLAY 0.638298 (-4225 3360);
PAINT MONO (-4225 3360);
DISPLAY INVISIBLE (-4225 3360);
WIRE 16 -1 (-2950 3350)(-1975 3350);
FORCEPROP 2 LAST SIG_NAME UART_CPU0_LVC3_UART0_TX
J 0
(-2725 3360);
DISPLAY 0.489362 (-2725 3360);
WIRE 16 -1 (-3875 1425)(-3050 1425);
FORCEPROP 2 LAST SIG_NAME UART_CPU0_LVC3_UART0_R_RX
J 0
(-3735 1435);
DISPLAY 0.489362 (-3735 1435);
WIRE 16 -1 (-2850 1425)(-2575 1425);
FORCEPROP 2 LAST SIG_NAME UART_CPU0_LVC3_UART0_RX
J 0
(-2710 1435);
DISPLAY 0.489362 (-2710 1435);
FORCEPROP 2 LASTPROP $XR0 164 
J 0
(-2980 1435);
DISPLAY 0.638298 (-2980 1435);
PAINT MONO (-2980 1435);
WIRE 16 -1 (-1550 1425)(-2575 1425);
WIRE 16 -1 (-2575 1425)(-2575 1250);
WIRE 16 -1 (-4925 3650)(-5050 3650);
WIRE 16 -1 (-5050 3650)(-5050 3875);
WIRE 16 -1 (-5175 3875)(-5050 3875);
WIRE 16 -1 (-5050 3875)(-5050 3900);
WIRE 16 -1 (-5175 3825)(-5175 3875);
WIRE 16 -1 (-6650 3450)(-4925 3450);
FORCEPROP 2 LAST SIG_NAME UART_CPU0_SCM_UART1_TX
J 0
(-6625 3460);
DISPLAY 0.489362 (-6625 3460);
WIRE 16 -1 (-6650 3350)(-4925 3350);
FORCEPROP 2 LAST SIG_NAME UART_CPU0_UART0_TX
J 0
(-6625 3360);
DISPLAY 0.489362 (-6625 3360);
WIRE 16 -1 (-5850 3050)(-4925 3050);
WIRE 16 -1 (-5850 3150)(-5850 3050);
WIRE 16 -1 (-5850 3050)(-6100 3050);
WIRE 16 -1 (-6100 3050)(-6100 3125);
WIRE 16 -1 (-4925 3150)(-5850 3150);
WIRE 16 -1 (-4125 3650)(-4000 3650);
WIRE 16 -1 (-4000 3650)(-4000 3875);
WIRE 16 -1 (-3850 3875)(-4000 3875);
WIRE 16 -1 (-4000 3875)(-4000 3925);
WIRE 16 -1 (-3850 3825)(-3850 3875);
WIRE 16 -1 (-5850 2950)(-4925 2950);
FORCEPROP 2 LAST SIG_NAME UART_LS_EN_N
J 0
(-5710 2960);
DISPLAY 0.489362 (-5710 2960);
WIRE 16 -1 (-4125 3300)(-1975 3300);
FORCEPROP 2 LAST SIG_NAME UART_CPU0_LVC3_UART0_R_RX
J 0
(-3985 3310);
DISPLAY 0.489362 (-3985 3310);
WIRE 16 -1 (-4125 3400)(-2000 3400);
FORCEPROP 2 LAST SIG_NAME UART_CPU0_SCM_LVC3_UART1_R_RX
J 0
(-3985 3410);
DISPLAY 0.489362 (-3985 3410);
WIRE 16 -1 (-1550 1475)(-2775 1475);
FORCEPROP 2 LAST SIG_NAME UART_CPU0_LVC3_UART0_TX
J 0
(-2710 1485);
DISPLAY 0.489362 (-2710 1485);
WIRE 16 -1 (-2775 1475)(-2775 1250);
WIRE 16 -1 (-3875 1475)(-2775 1475);
WIRE 16 -1 (-7675 1975)(-7075 1975);
FORCEPROP 2 LAST SIG_NAME UART_LS_EN
J 0
(-7610 1985);
DISPLAY 0.489362 (-7610 1985);
DOT 1 (-2775 1475);
DOT 1 (-2575 1425);
DOT 1 (-5050 3875);
DOT 1 (-2150 950);
DOT 1 (-6875 2325);
DOT 1 (-4000 3875);
DOT 1 (-1250 4625);
DOT 1 (-1050 4625);
DOT 1 (-825 4625);
DOT 1 (-7425 4350);
DOT 1 (-7625 4350);
DOT 1 (-7850 4350);
DOT 1 (-5850 3050);
FORCENOTE
TO SCM UART1
(-2575 5075) 0;
DISPLAY LEFT (-2575 5075);
DISPLAY 3.936170 (-2575 5075);
PAINT WHITE (-2575 5075);
FORCENOTE
CPU0 UART1
(-9100 3300) 0;
DISPLAY LEFT (-9100 3300);
DISPLAY 3.936170 (-9100 3300);
PAINT WHITE (-9100 3300);
QUIT
